G04 ================== begin FILE IDENTIFICATION RECORD ==================*
G04 Layout Name:  13919-sa.brd*
G04 Film Name:    DRILL*
G04 File Format:  Gerber RS274X*
G04 File Origin:  Cadence Allegro 16.5-S039*
G04 Origin Date:  Fri Nov 22 15:27:00 2013*
G04 *
G04 Layer:  MANUFACTURING/NCLEGEND-1-4*
G04 Layer:  MANUFACTURING/DRILL SIZE*
G04 Layer:  DRAWING FORMAT/LAYER_PCB_STORY*
G04 Layer:  DRAWING FORMAT/LAYER_DRILL*
G04 Layer:  BOARD GEOMETRY/PANEL_OUTLINE*
G04 *
G04 Offset:    (0.00 0.00)*
G04 Mirror:    No*
G04 Mode:      Positive*
G04 Rotation:  0*
G04 FullContactRelief:  No*
G04 UndefLineWidth:     6.00*
G04 ================== end FILE IDENTIFICATION RECORD ====================*
%FSLAX35Y35*MOIN*%
%IR0*IPPOS*OFA0.00000B0.00000*MIA0B0*SFA1.00000B1.00000*%
%AMMACRO10*
1,1,.006,.006,0.0*
20,1,.006,.006,0.0,-.006,0.0,0.0*
1,1,.006,-.006,0.0*
1,1,.006,0.0,.006*
20,1,.006,0.0,.006,0.0,-.006,0.0*
1,1,.006,0.0,-.006*
1,1,.006,.003,0.0*
20,1,.006,.003,0.0,.003,.006,0.0*
1,1,.006,.003,.006*
20,1,.006,.003,.006,.0018,.0048,0.0*
1,1,.006,.0018,.0048*
1,1,.006,.0018,0.0*
20,1,.006,.0018,0.0,.0042,0.0,0.0*
1,1,.006,.0042,0.0*
%
%ADD10MACRO10*%
%AMMACRO11*
1,1,.006,.008,.008*
20,1,.006,.008,.008,.008,-.008,0.0*
1,1,.006,.008,-.008*
20,1,.006,.008,-.008,-.008,-.008,0.0*
1,1,.006,-.008,-.008*
20,1,.006,-.008,-.008,-.008,.008,0.0*
1,1,.006,-.008,.008*
20,1,.006,-.008,.008,.008,.008,0.0*
1,1,.006,.008,.008*
1,1,.006,-.00253,.00267*
20,1,.006,-.00253,.00267,-.00173,.00347,0.0*
1,1,.006,-.00173,.00347*
20,1,.006,-.00173,.00347,-.0008,.00387,0.0*
1,1,.006,-.0008,.00387*
20,1,.006,-.0008,.00387,.00027,.004,0.0*
1,1,.006,.00027,.004*
20,1,.006,.00027,.004,.0016,.00373,0.0*
1,1,.006,.0016,.00373*
20,1,.006,.0016,.00373,.00253,.00307,0.0*
1,1,.006,.00253,.00307*
20,1,.006,.00253,.00307,.0028,.00227,0.0*
1,1,.006,.0028,.00227*
20,1,.006,.0028,.00227,.00267,.00147,0.0*
1,1,.006,.00267,.00147*
20,1,.006,.00267,.00147,.00213,.0008,0.0*
1,1,.006,.00213,.0008*
20,1,.006,.00213,.0008,-.00053,-.00053,0.0*
1,1,.006,-.00053,-.00053*
20,1,.006,-.00053,-.00053,-.00173,-.00147,0.0*
1,1,.006,-.00173,-.00147*
20,1,.006,-.00173,-.00147,-.00253,-.0028,0.0*
1,1,.006,-.00253,-.0028*
20,1,.006,-.00253,-.0028,-.0028,-.004,0.0*
1,1,.006,-.0028,-.004*
20,1,.006,-.0028,-.004,.0028,-.004,0.0*
1,1,.006,.0028,-.004*
%
%ADD11MACRO11*%
%AMMACRO12*
1,1,.006,.019261,-.0465*
20,1,.006,.019261,-.0465,-.019261,-.0465,0.0*
1,1,.006,-.019261,-.0465*
20,1,.006,-.019261,-.0465,-.0465,-.019261,0.0*
1,1,.006,-.0465,-.019261*
20,1,.006,-.0465,-.019261,-.0465,.019261,0.0*
1,1,.006,-.0465,.019261*
20,1,.006,-.0465,.019261,-.019261,.0465,0.0*
1,1,.006,-.019261,.0465*
20,1,.006,-.019261,.0465,.019261,.0465,0.0*
1,1,.006,.019261,.0465*
20,1,.006,.019261,.0465,.0465,.019261,0.0*
1,1,.006,.0465,.019261*
20,1,.006,.0465,.019261,.0465,-.019261,0.0*
1,1,.006,.0465,-.019261*
20,1,.006,.0465,-.019261,.019261,-.0465,0.0*
1,1,.006,.019261,-.0465*
1,1,.006,-.01705,-.01628*
20,1,.006,-.01705,-.01628,-.0124,-.02015,0.0*
1,1,.006,-.0124,-.02015*
20,1,.006,-.0124,-.02015,-.00698,-.02248,0.0*
1,1,.006,-.00698,-.02248*
20,1,.006,-.00698,-.02248,0.0,-.02325,0.0*
1,1,.006,0.0,-.02325*
20,1,.006,0.0,-.02325,.00698,-.0217,0.0*
1,1,.006,.00698,-.0217*
20,1,.006,.00698,-.0217,.0124,-.0186,0.0*
1,1,.006,.0124,-.0186*
20,1,.006,.0124,-.0186,.01628,-.01318,0.0*
1,1,.006,.01628,-.01318*
20,1,.006,.01628,-.01318,.01705,-.00698,0.0*
1,1,.006,.01705,-.00698*
20,1,.006,.01705,-.00698,.0155,-.00078,0.0*
1,1,.006,.0155,-.00078*
20,1,.006,.0155,-.00078,.01162,.0031,0.0*
1,1,.006,.01162,.0031*
20,1,.006,.01162,.0031,.0062,.0062,0.0*
1,1,.006,.0062,.0062*
20,1,.006,.0062,.0062,.00078,.00697,0.0*
1,1,.006,.00078,.00697*
20,1,.006,.00078,.00697,-.00465,.0062,0.0*
1,1,.006,-.00465,.0062*
20,1,.006,-.00465,.0062,-.01162,.0031,0.0*
1,1,.006,-.01162,.0031*
20,1,.006,-.01162,.0031,-.0093,.02325,0.0*
1,1,.006,-.0093,.02325*
20,1,.006,-.0093,.02325,.01162,.02325,0.0*
1,1,.006,.01162,.02325*
%
%ADD12MACRO12*%
%AMMACRO13*
1,1,.006,.0145,0.0*
20,1,.006,.0145,0.0,.00725,.012557,0.0*
1,1,.006,.00725,.012557*
20,1,.006,.00725,.012557,-.00725,.012557,0.0*
1,1,.006,-.00725,.012557*
20,1,.006,-.00725,.012557,-.0145,0.0,0.0*
1,1,.006,-.0145,0.0*
20,1,.006,-.0145,0.0,-.00725,-.012557,0.0*
1,1,.006,-.00725,-.012557*
20,1,.006,-.00725,-.012557,.00725,-.012557,0.0*
1,1,.006,.00725,-.012557*
20,1,.006,.00725,-.012557,.0145,0.0,0.0*
1,1,.006,.0145,0.0*
1,1,.006,-.00532,-.00435*
20,1,.006,-.00532,-.00435,-.00387,-.00604,0.0*
1,1,.006,-.00387,-.00604*
20,1,.006,-.00387,-.00604,-.00193,-.00701,0.0*
1,1,.006,-.00193,-.00701*
20,1,.006,-.00193,-.00701,.00024,-.00725,0.0*
1,1,.006,.00024,-.00725*
20,1,.006,.00024,-.00725,.00218,-.00701,0.0*
1,1,.006,.00218,-.00701*
20,1,.006,.00218,-.00701,.00411,-.0058,0.0*
1,1,.006,.00411,-.0058*
20,1,.006,.00411,-.0058,.00532,-.00435,0.0*
1,1,.006,.00532,-.00435*
20,1,.006,.00532,-.00435,.00556,-.0029,0.0*
1,1,.006,.00556,-.0029*
20,1,.006,.00556,-.0029,.00508,-.00121,0.0*
1,1,.006,.00508,-.00121*
20,1,.006,.00508,-.00121,.00338,0.0,0.0*
1,1,.006,.00338,0.0*
20,1,.006,.00338,0.0,.00169,.00048,0.0*
1,1,.006,.00169,.00048*
20,1,.006,.00169,.00048,-.00048,.00048,0.0*
1,1,.006,-.00048,.00048*
1,1,.006,.00169,.00048*
20,1,.006,.00169,.00048,.00314,.00121,0.0*
1,1,.006,.00314,.00121*
20,1,.006,.00314,.00121,.00435,.00242,0.0*
1,1,.006,.00435,.00242*
20,1,.006,.00435,.00242,.00483,.00387,0.0*
1,1,.006,.00483,.00387*
20,1,.006,.00483,.00387,.00435,.00532,0.0*
1,1,.006,.00435,.00532*
20,1,.006,.00435,.00532,.00314,.00652,0.0*
1,1,.006,.00314,.00652*
20,1,.006,.00314,.00652,.00097,.00725,0.0*
1,1,.006,.00097,.00725*
20,1,.006,.00097,.00725,-.00121,.00701,0.0*
1,1,.006,-.00121,.00701*
20,1,.006,-.00121,.00701,-.00338,.00604,0.0*
1,1,.006,-.00338,.00604*
%
%ADD13MACRO13*%
%AMMACRO14*
1,1,.006,0.0,.043*
20,1,.006,0.0,.043,-.037239,.0215,0.0*
1,1,.006,-.037239,.0215*
20,1,.006,-.037239,.0215,-.037239,-.0215,0.0*
1,1,.006,-.037239,-.0215*
20,1,.006,-.037239,-.0215,0.0,-.043,0.0*
1,1,.006,0.0,-.043*
20,1,.006,0.0,-.043,.037239,-.0215,0.0*
1,1,.006,.037239,-.0215*
20,1,.006,.037239,-.0215,.037239,.0215,0.0*
1,1,.006,.037239,.0215*
20,1,.006,.037239,.0215,0.0,.043,0.0*
1,1,.006,0.0,.043*
1,1,.006,.0086,-.0215*
20,1,.006,.0086,-.0215,.0086,.0215,0.0*
1,1,.006,.0086,.0215*
20,1,.006,.0086,.0215,-.01792,-.00932,0.0*
1,1,.006,-.01792,-.00932*
20,1,.006,-.01792,-.00932,.01792,-.00932,0.0*
1,1,.006,.01792,-.00932*
%
%ADD14MACRO14*%
%ADD15C,.02*%
%ADD16C,.006*%
G75*
%LPD*%
G75*
G54D10*
X45633Y31600D03*
X38133Y31500D03*
X35363Y37960D03*
X108333Y31600D03*
X100733Y31500D03*
X92533D03*
X84233Y31400D03*
X77233Y31700D03*
X68633Y31400D03*
X60633Y31500D03*
X52733Y31400D03*
X163733Y31500D03*
X155433Y31600D03*
X147833Y31500D03*
X139733D03*
X132333Y31600D03*
X124233D03*
X116233Y31500D03*
X226933D03*
X219033Y31600D03*
X210633Y31500D03*
X202433Y31400D03*
X194933Y31600D03*
X188976Y31543D03*
X179133Y31600D03*
X171333D03*
X288533Y31020D03*
X280933Y31400D03*
X274433D03*
X266033Y31020D03*
X258233Y31300D03*
X249533Y31400D03*
X242333Y31600D03*
X234333Y31400D03*
X329633Y31100D03*
X338583Y32050D03*
X295275Y31658D03*
X850500Y173510D03*
G54D11*
X30680Y42700D03*
X23720Y37880D03*
X30833Y58700D03*
X21533Y59100D03*
X17033Y53450D03*
X15633Y69500D03*
X25733Y53450D03*
X15333Y62700D03*
X343019Y32504D03*
X347544Y32400D03*
X344360Y43670D03*
X343700Y53890D03*
X340080Y47960D03*
X340010Y58570D03*
X354650Y89890D03*
X355770Y78680D03*
X357350Y72160D03*
X850500Y145410D03*
G54D12*
X16538Y78346D03*
X304528D03*
X850500Y61110D03*
G54D13*
X47243Y65551D03*
X43308Y73426D03*
X39373Y65551D03*
X35433Y73426D03*
X31498Y65551D03*
X27558Y73426D03*
X23623Y65551D03*
X47243Y91141D03*
X43308Y83266D03*
X39373Y91141D03*
X35433Y83266D03*
X31498Y91141D03*
X27558Y83266D03*
X23623Y91141D03*
X110238Y65551D03*
X106298Y73426D03*
X102363Y65551D03*
X98428Y73426D03*
X94488Y65551D03*
X90553Y73426D03*
X86613Y65551D03*
X82678Y73426D03*
X78743Y65551D03*
X74803Y73426D03*
X70868Y65551D03*
X66928Y73426D03*
X62993Y65551D03*
X59058Y73426D03*
X55118Y65551D03*
X51183Y73426D03*
X110238Y91141D03*
X106298Y83266D03*
X102363Y91141D03*
X98428Y83266D03*
X94488Y91141D03*
X90553Y83266D03*
X86613Y91141D03*
X82678Y83266D03*
X78743Y91141D03*
X74803Y83266D03*
X70868Y91141D03*
X66928Y83266D03*
X62993Y91141D03*
X59058Y83266D03*
X55118Y91141D03*
X51183Y83266D03*
X169293Y73426D03*
X165353Y65551D03*
X161418Y73426D03*
X157483Y65551D03*
X153543Y73426D03*
X149608Y65551D03*
X145668Y73426D03*
X141733Y65551D03*
X137798Y73426D03*
X133858Y65551D03*
X129923Y73426D03*
X125983Y65551D03*
X122048Y73426D03*
X118113Y65551D03*
X114173Y73426D03*
X169293Y83266D03*
X165353Y91141D03*
X161418Y83266D03*
X157483Y91141D03*
X153543Y83266D03*
X149608Y91141D03*
X145668Y83266D03*
X141733Y91141D03*
X137798Y83266D03*
X133858Y91141D03*
X129923Y83266D03*
X125983Y91141D03*
X122048Y83266D03*
X118113Y91141D03*
X114173Y83266D03*
X232283Y73426D03*
X228348Y65551D03*
X224408Y73426D03*
X220473Y65551D03*
X216538Y73426D03*
X212598Y65551D03*
X208663Y73426D03*
X204723Y65551D03*
X200788Y73426D03*
X196853Y65551D03*
X192913Y73426D03*
X188978Y65551D03*
X185038Y73426D03*
X181103Y65551D03*
X177168Y73426D03*
X173228Y65551D03*
X232283Y83266D03*
X228348Y91141D03*
X224408Y83266D03*
X220473Y91141D03*
X216538Y83266D03*
X212598Y91141D03*
X208663Y83266D03*
X204723Y91141D03*
X200788Y83266D03*
X196853Y91141D03*
X192913Y83266D03*
X188978Y91141D03*
X185038Y83266D03*
X181103Y91141D03*
X177168Y83266D03*
X173228Y91141D03*
X291338Y65551D03*
X287403Y73426D03*
X283463Y65551D03*
X279528Y73426D03*
X275593Y65551D03*
X271653Y73426D03*
X267718Y65551D03*
X263778Y73426D03*
X259843Y65551D03*
X255908Y73426D03*
X251968Y65551D03*
X248033Y73426D03*
X244093Y65551D03*
X240158Y73426D03*
X236223Y65551D03*
X291338Y91141D03*
X287403Y83266D03*
X283463Y91141D03*
X279528Y83266D03*
X275593Y91141D03*
X271653Y83266D03*
X267718Y91141D03*
X263778Y83266D03*
X259843Y91141D03*
X255908Y83266D03*
X251968Y91141D03*
X248033Y83266D03*
X244093Y91141D03*
X240158Y83266D03*
X236223Y91141D03*
X350393Y73426D03*
X346458Y65551D03*
X342518Y73426D03*
X338583Y65551D03*
X334648Y73426D03*
X330708Y65551D03*
X326773Y73426D03*
X322833Y65551D03*
X318898Y73426D03*
X314963Y65551D03*
X311023Y73426D03*
X299213Y65551D03*
X295278Y73426D03*
X350393Y83266D03*
X346458Y91141D03*
X342518Y83266D03*
X338583Y91141D03*
X334648Y83266D03*
X330708Y91141D03*
X326773Y83266D03*
X322833Y91141D03*
X318898Y83266D03*
X314963Y91141D03*
X311023Y83266D03*
X299213Y91141D03*
X295278Y83266D03*
X850500Y117310D03*
G54D14*
X8950Y97440D03*
X8750Y50860D03*
X-2462Y651994D03*
X364570Y96910D03*
X758452Y17317D03*
X755722Y677788D03*
X850500Y89210D03*
G54D15*
G01X-67189Y-77263D02*
G02I-12000J0D01*
G01X-72339D02*
G02I-6850J0D01*
G01X-79189Y-93263D02*
Y-61263D01*
G01X-63189Y-77263D02*
X-95189D01*
G01X-63189Y-93263D02*
Y-173263D01*
G01D02*
X1156611D01*
G01X-63189Y-93263D02*
X1156611D01*
G01X-63189Y-128763D02*
X1156611D01*
G01X369111Y-93263D02*
Y-173263D01*
G01X506611Y-93263D02*
Y-173263D01*
G01X621611Y-93263D02*
Y-173263D01*
G01X789111Y-93263D02*
Y-173263D01*
G01X959111Y-93263D02*
Y-173263D01*
G01X1156611Y-93263D02*
Y-173263D01*
G01X1184611Y-77263D02*
G02I-12000J0D01*
G01X1179461D02*
G02I-6850J0D01*
G01X1172611Y-93263D02*
Y-61263D01*
G01X1188611Y-77263D02*
X1156611D01*
G54D16*
G01X-44374Y-163263D02*
Y-145763D01*
G01X-35204D02*
Y-163263D01*
G01Y-154513D02*
X-44374D01*
G01X-22289Y-163263D02*
X-23599Y-162971D01*
X-24909Y-161805D01*
X-25783Y-159763D01*
X-26219Y-157430D01*
X-25783Y-155096D01*
X-24909Y-153055D01*
X-23599Y-151888D01*
X-22289Y-151597D01*
X-20979Y-151888D01*
X-19669Y-153055D01*
X-18796Y-155096D01*
X-18577Y-157430D01*
X-18796Y-159763D01*
X-19669Y-161805D01*
X-20979Y-162971D01*
X-22289Y-163263D01*
G01X-8501D02*
Y-151597D01*
G01Y-154513D02*
X-7627Y-153055D01*
X-6317Y-151888D01*
X-4571Y-151597D01*
X-3043Y-151888D01*
X-1732Y-153055D01*
X-1077Y-155096D01*
Y-163263D01*
G01X9436Y-155388D02*
X16423D01*
X15768Y-153346D01*
X14676Y-152180D01*
X13148Y-151597D01*
X11619Y-151888D01*
X10309Y-152763D01*
X9436Y-154805D01*
X8999Y-156555D01*
Y-158305D01*
X9436Y-160055D01*
X10528Y-161805D01*
X11838Y-162971D01*
X13366Y-163263D01*
X14894Y-162680D01*
X16423Y-160930D01*
G01X25626Y-168513D02*
X26936Y-169096D01*
X28683Y-168513D01*
X29774Y-167347D01*
X30648Y-165888D01*
X31957Y-161222D01*
X34796Y-151597D01*
G01X27809D02*
X31957Y-161222D01*
G01X66957Y-153930D02*
X67831Y-153055D01*
X68486Y-151597D01*
X68923Y-149554D01*
X68486Y-147805D01*
X67613Y-146638D01*
X66084Y-145763D01*
X60189D01*
Y-163263D01*
X67394D01*
X68923Y-162097D01*
X69796Y-160346D01*
X70233Y-158305D01*
X69796Y-156263D01*
X68486Y-154513D01*
X66957Y-153930D01*
X60189D01*
G01X86641Y-163263D02*
Y-151597D01*
G01Y-153638D02*
X85768Y-152472D01*
X84457Y-151888D01*
X82929Y-151597D01*
X81401Y-152180D01*
X80091Y-153346D01*
X79217Y-155096D01*
X78781Y-157430D01*
X79217Y-159763D01*
X80091Y-161513D01*
X81401Y-162680D01*
X82929Y-163263D01*
X84457Y-162971D01*
X85768Y-162097D01*
X86641Y-160930D01*
G01X104141Y-145763D02*
Y-163263D01*
G01Y-160639D02*
X103268Y-162097D01*
X101957Y-162971D01*
X100429Y-163263D01*
X98683Y-162680D01*
X97373Y-161222D01*
X96499Y-159472D01*
X96281Y-157430D01*
X96499Y-155388D01*
X97373Y-153638D01*
X98683Y-152180D01*
X100429Y-151597D01*
X101957Y-151888D01*
X103049Y-152472D01*
X104141Y-153638D01*
G01X114654Y-167638D02*
X116183Y-168805D01*
X117929Y-169096D01*
X119457Y-168805D01*
X120768Y-167347D01*
X121641Y-165305D01*
Y-151597D01*
G01Y-153930D02*
X120768Y-152763D01*
X119457Y-151888D01*
X117929Y-151597D01*
X116183Y-152180D01*
X115091Y-153346D01*
X114217Y-155388D01*
X113781Y-157430D01*
X113999Y-159180D01*
X114873Y-161222D01*
X116183Y-162680D01*
X117929Y-163263D01*
X119239Y-162971D01*
X120768Y-161805D01*
X121641Y-160639D01*
G01X131936Y-155388D02*
X138923D01*
X138268Y-153346D01*
X137176Y-152180D01*
X135648Y-151597D01*
X134119Y-151888D01*
X132809Y-152763D01*
X131936Y-154805D01*
X131499Y-156555D01*
Y-158305D01*
X131936Y-160055D01*
X133028Y-161805D01*
X134338Y-162971D01*
X135866Y-163263D01*
X137394Y-162680D01*
X138923Y-160930D01*
G01X149654Y-163263D02*
Y-151597D01*
G01Y-153930D02*
X150746Y-152763D01*
X151838Y-151888D01*
X153366Y-151597D01*
X154457Y-151888D01*
X155768Y-152763D01*
G01X183344Y-163263D02*
Y-145763D01*
X188803D01*
X190549Y-146638D01*
X191641Y-147805D01*
X192078Y-150138D01*
X191641Y-152472D01*
X190331Y-153930D01*
X188803Y-154805D01*
X183344D01*
G01X188803D02*
X192078Y-163263D01*
G01X205211Y-151597D02*
Y-163263D01*
G01Y-146930D02*
X204774Y-146638D01*
Y-146055D01*
X205211Y-145763D01*
X205648Y-146055D01*
Y-146638D01*
X205211Y-146930D01*
G01X219436Y-161222D02*
X220528Y-162388D01*
X222056Y-163263D01*
X223366D01*
X224676Y-162680D01*
X225549Y-161805D01*
X225986Y-160639D01*
X225768Y-158888D01*
X224894Y-158013D01*
X220964Y-156263D01*
X220091Y-154221D01*
X220528Y-152763D01*
X221401Y-151888D01*
X222711Y-151597D01*
X224021Y-151888D01*
X225331Y-152763D01*
G01X236936Y-155388D02*
X243923D01*
X243268Y-153346D01*
X242176Y-152180D01*
X240648Y-151597D01*
X239119Y-151888D01*
X237809Y-152763D01*
X236936Y-154805D01*
X236499Y-156555D01*
Y-158305D01*
X236936Y-160055D01*
X238028Y-161805D01*
X239338Y-162971D01*
X240866Y-163263D01*
X242394Y-162680D01*
X243923Y-160930D01*
G01X254654Y-163263D02*
Y-151597D01*
G01Y-153930D02*
X255746Y-152763D01*
X256838Y-151888D01*
X258366Y-151597D01*
X259457Y-151888D01*
X260768Y-152763D01*
G01X297514Y-147222D02*
X296204Y-146346D01*
X294676Y-145763D01*
X292929D01*
X290964Y-146638D01*
X289436Y-148096D01*
X288344Y-149847D01*
X287471Y-152763D01*
X287252Y-155388D01*
X287689Y-158013D01*
X288344Y-159763D01*
X289654Y-161513D01*
X291183Y-162680D01*
X292711Y-163263D01*
X294239D01*
X295768Y-162680D01*
X297078Y-161805D01*
X298170Y-160639D01*
G01X314141Y-163263D02*
Y-151597D01*
G01Y-153638D02*
X313268Y-152472D01*
X311957Y-151888D01*
X310429Y-151597D01*
X308901Y-152180D01*
X307591Y-153346D01*
X306717Y-155096D01*
X306281Y-157430D01*
X306717Y-159763D01*
X307591Y-161513D01*
X308901Y-162680D01*
X310429Y-163263D01*
X311957Y-162971D01*
X313268Y-162097D01*
X314141Y-160930D01*
G01X324654Y-163263D02*
Y-151597D01*
G01Y-153930D02*
X325746Y-152763D01*
X326838Y-151888D01*
X328366Y-151597D01*
X329457Y-151888D01*
X330768Y-152763D01*
G01X349141Y-145763D02*
Y-163263D01*
G01Y-160639D02*
X348268Y-162097D01*
X346957Y-162971D01*
X345429Y-163263D01*
X343683Y-162680D01*
X342373Y-161222D01*
X341499Y-159472D01*
X341281Y-157430D01*
X341499Y-155388D01*
X342373Y-153638D01*
X343683Y-152180D01*
X345429Y-151597D01*
X346957Y-151888D01*
X348049Y-152472D01*
X349141Y-153638D01*
G01X112034Y-118263D02*
Y-100763D01*
X117711Y-115346D01*
X123388Y-100763D01*
Y-118263D01*
G01X135211D02*
X133901Y-117971D01*
X132591Y-116805D01*
X131717Y-114763D01*
X131281Y-112430D01*
X131717Y-110096D01*
X132591Y-108055D01*
X133901Y-106888D01*
X135211Y-106597D01*
X136521Y-106888D01*
X137831Y-108055D01*
X138704Y-110096D01*
X138923Y-112430D01*
X138704Y-114763D01*
X137831Y-116805D01*
X136521Y-117971D01*
X135211Y-118263D01*
G01X156641Y-100763D02*
Y-118263D01*
G01Y-115639D02*
X155768Y-117097D01*
X154457Y-117971D01*
X152929Y-118263D01*
X151183Y-117680D01*
X149873Y-116222D01*
X148999Y-114472D01*
X148781Y-112430D01*
X148999Y-110388D01*
X149873Y-108638D01*
X151183Y-107180D01*
X152929Y-106597D01*
X154457Y-106888D01*
X155549Y-107472D01*
X156641Y-108638D01*
G01X166936Y-110388D02*
X173923D01*
X173268Y-108346D01*
X172176Y-107180D01*
X170648Y-106597D01*
X169119Y-106888D01*
X167809Y-107763D01*
X166936Y-109805D01*
X166499Y-111555D01*
Y-113305D01*
X166936Y-115055D01*
X168028Y-116805D01*
X169338Y-117971D01*
X170866Y-118263D01*
X172394Y-117680D01*
X173923Y-115930D01*
G01X187711Y-118263D02*
Y-100763D01*
G01X402811Y-163263D02*
Y-145763D01*
X400191Y-149263D01*
G01Y-163263D02*
X405431D01*
G01X415508Y-159763D02*
X416817Y-161805D01*
X418564Y-162971D01*
X420529Y-163263D01*
X422276Y-162971D01*
X424023Y-161513D01*
X425114Y-159763D01*
X425333Y-158013D01*
X424896Y-155972D01*
X423368Y-154513D01*
X421839Y-153930D01*
X419874D01*
G01X421839D02*
X423149Y-153055D01*
X424241Y-151597D01*
X424678Y-149847D01*
X424241Y-148096D01*
X423149Y-146638D01*
X421184Y-145763D01*
X419219Y-146055D01*
X417254Y-147222D01*
G01X434099Y-161222D02*
X435628Y-162680D01*
X437374Y-163263D01*
X439121Y-162680D01*
X440649Y-160930D01*
X441741Y-158305D01*
X442178Y-155680D01*
Y-152472D01*
X441741Y-149847D01*
X440649Y-147513D01*
X439339Y-146346D01*
X437811Y-145763D01*
X436064Y-146346D01*
X434754Y-147513D01*
X433881Y-149263D01*
X433444Y-151597D01*
X433881Y-153638D01*
X434973Y-155680D01*
X436283Y-156847D01*
X437811Y-157138D01*
X439557Y-156555D01*
X440868Y-155096D01*
X442178Y-152472D01*
G01X455311Y-163263D02*
Y-145763D01*
X452691Y-149263D01*
G01Y-163263D02*
X457931D01*
G01X469099Y-161222D02*
X470628Y-162680D01*
X472374Y-163263D01*
X474121Y-162680D01*
X475649Y-160930D01*
X476741Y-158305D01*
X477178Y-155680D01*
Y-152472D01*
X476741Y-149847D01*
X475649Y-147513D01*
X474339Y-146346D01*
X472811Y-145763D01*
X471064Y-146346D01*
X469754Y-147513D01*
X468881Y-149263D01*
X468444Y-151597D01*
X468881Y-153638D01*
X469973Y-155680D01*
X471283Y-156847D01*
X472811Y-157138D01*
X474557Y-156555D01*
X475868Y-155096D01*
X477178Y-152472D01*
G01X389694Y-118263D02*
Y-100763D01*
X394934D01*
X396681Y-101638D01*
X397991Y-103680D01*
X398428Y-106013D01*
X397991Y-108346D01*
X396899Y-110096D01*
X394934Y-110972D01*
X389694D01*
G01X416364Y-102222D02*
X415054Y-101346D01*
X413526Y-100763D01*
X411779D01*
X409814Y-101638D01*
X408286Y-103096D01*
X407194Y-104847D01*
X406321Y-107763D01*
X406102Y-110388D01*
X406539Y-113013D01*
X407194Y-114763D01*
X408504Y-116513D01*
X410033Y-117680D01*
X411561Y-118263D01*
X413089D01*
X414618Y-117680D01*
X415928Y-116805D01*
X417020Y-115639D01*
G01X430807Y-108930D02*
X431681Y-108055D01*
X432336Y-106597D01*
X432773Y-104554D01*
X432336Y-102805D01*
X431463Y-101638D01*
X429934Y-100763D01*
X424039D01*
Y-118263D01*
X431244D01*
X432773Y-117097D01*
X433646Y-115346D01*
X434083Y-113305D01*
X433646Y-111263D01*
X432336Y-109513D01*
X430807Y-108930D01*
X424039D01*
G01X440011Y-124096D02*
X453111D01*
G01X459039Y-118263D02*
Y-100763D01*
X469083Y-118263D01*
Y-100763D01*
G01X481561Y-118263D02*
X479814Y-117971D01*
X478286Y-116805D01*
X476976Y-115055D01*
X476102Y-113013D01*
X475666Y-110680D01*
Y-108346D01*
X476102Y-106013D01*
X476976Y-103971D01*
X478286Y-102222D01*
X479814Y-101055D01*
X481561Y-100763D01*
X483307Y-101055D01*
X484836Y-102222D01*
X486146Y-103971D01*
X487020Y-106013D01*
X487456Y-108346D01*
Y-110680D01*
X487020Y-113013D01*
X486146Y-115055D01*
X484836Y-116805D01*
X483307Y-117971D01*
X481561Y-118263D01*
G01X532402Y-100763D02*
X537861Y-118263D01*
X543320Y-100763D01*
G01X559728Y-118263D02*
X550994D01*
Y-100763D01*
X559728D01*
G01X556234Y-109221D02*
X550994D01*
G01X568494Y-118263D02*
Y-100763D01*
X573953D01*
X575699Y-101638D01*
X576791Y-102805D01*
X577228Y-105138D01*
X576791Y-107472D01*
X575481Y-108930D01*
X573953Y-109805D01*
X568494D01*
G01X573953D02*
X577228Y-118263D01*
G01X590361Y-118846D02*
X589924Y-118555D01*
Y-117971D01*
X590361Y-117680D01*
X590798Y-117971D01*
Y-118555D01*
X590361Y-118846D01*
G01X550776Y-160930D02*
X552523Y-162388D01*
X554488Y-163263D01*
X556234D01*
X557981Y-162388D01*
X559291Y-160930D01*
X559946Y-158888D01*
X559509Y-156847D01*
X558418Y-155096D01*
X556453Y-153930D01*
X553833Y-153346D01*
X552304Y-152180D01*
X551649Y-150138D01*
X552086Y-148096D01*
X553178Y-146638D01*
X554706Y-145763D01*
X556234D01*
X557763Y-146346D01*
X559073Y-147805D01*
G01X567402Y-163263D02*
X572861Y-145763D01*
X578320Y-163263D01*
G01X576354Y-157138D02*
X569367D01*
G01X665508Y-163263D02*
Y-145763D01*
X669874D01*
X671621Y-146638D01*
X672931Y-147805D01*
X674023Y-149554D01*
X674896Y-151597D01*
X675114Y-154513D01*
X674896Y-157430D01*
X674023Y-159472D01*
X672931Y-161222D01*
X671621Y-162388D01*
X669874Y-163263D01*
X665508D01*
G01X683444D02*
Y-145763D01*
X688903D01*
X690649Y-146638D01*
X691741Y-147805D01*
X692178Y-150138D01*
X691741Y-152472D01*
X690431Y-153930D01*
X688903Y-154805D01*
X683444D01*
G01X688903D02*
X692178Y-163263D01*
G01X702691Y-145763D02*
X707931D01*
G01X705311D02*
Y-163263D01*
G01X702691D02*
X707931D01*
G01X718444Y-145763D02*
Y-163263D01*
X727178D01*
G01X735944Y-145763D02*
Y-163263D01*
X744678D01*
G01X665944Y-100763D02*
Y-118263D01*
X674678D01*
G01X691741D02*
Y-106597D01*
G01Y-108638D02*
X690868Y-107472D01*
X689557Y-106888D01*
X688029Y-106597D01*
X686501Y-107180D01*
X685191Y-108346D01*
X684317Y-110096D01*
X683881Y-112430D01*
X684317Y-114763D01*
X685191Y-116513D01*
X686501Y-117680D01*
X688029Y-118263D01*
X689557Y-117971D01*
X690868Y-117097D01*
X691741Y-115930D01*
G01X700726Y-123513D02*
X702036Y-124096D01*
X703783Y-123513D01*
X704874Y-122347D01*
X705748Y-120888D01*
X707057Y-116222D01*
X709896Y-106597D01*
G01X702909D02*
X707057Y-116222D01*
G01X719536Y-110388D02*
X726523D01*
X725868Y-108346D01*
X724776Y-107180D01*
X723248Y-106597D01*
X721719Y-106888D01*
X720409Y-107763D01*
X719536Y-109805D01*
X719099Y-111555D01*
Y-113305D01*
X719536Y-115055D01*
X720628Y-116805D01*
X721938Y-117971D01*
X723466Y-118263D01*
X724994Y-117680D01*
X726523Y-115930D01*
G01X737254Y-118263D02*
Y-106597D01*
G01Y-108930D02*
X738346Y-107763D01*
X739438Y-106888D01*
X740966Y-106597D01*
X742057Y-106888D01*
X743368Y-107763D01*
G01X808058Y-118263D02*
Y-100763D01*
X812424D01*
X814171Y-101638D01*
X815481Y-102805D01*
X816573Y-104554D01*
X817446Y-106597D01*
X817664Y-109513D01*
X817446Y-112430D01*
X816573Y-114472D01*
X815481Y-116222D01*
X814171Y-117388D01*
X812424Y-118263D01*
X808058D01*
G01X827086Y-110388D02*
X834073D01*
X833418Y-108346D01*
X832326Y-107180D01*
X830798Y-106597D01*
X829269Y-106888D01*
X827959Y-107763D01*
X827086Y-109805D01*
X826649Y-111555D01*
Y-113305D01*
X827086Y-115055D01*
X828178Y-116805D01*
X829488Y-117971D01*
X831016Y-118263D01*
X832544Y-117680D01*
X834073Y-115930D01*
G01X844586Y-116222D02*
X845678Y-117388D01*
X847206Y-118263D01*
X848516D01*
X849826Y-117680D01*
X850699Y-116805D01*
X851136Y-115639D01*
X850918Y-113888D01*
X850044Y-113013D01*
X846114Y-111263D01*
X845241Y-109221D01*
X845678Y-107763D01*
X846551Y-106888D01*
X847861Y-106597D01*
X849171Y-106888D01*
X850481Y-107763D01*
G01X865361Y-106597D02*
Y-118263D01*
G01Y-101930D02*
X864924Y-101638D01*
Y-101055D01*
X865361Y-100763D01*
X865798Y-101055D01*
Y-101638D01*
X865361Y-101930D01*
G01X879804Y-122638D02*
X881333Y-123805D01*
X883079Y-124096D01*
X884607Y-123805D01*
X885918Y-122347D01*
X886791Y-120305D01*
Y-106597D01*
G01Y-108930D02*
X885918Y-107763D01*
X884607Y-106888D01*
X883079Y-106597D01*
X881333Y-107180D01*
X880241Y-108346D01*
X879367Y-110388D01*
X878931Y-112430D01*
X879149Y-114180D01*
X880023Y-116222D01*
X881333Y-117680D01*
X883079Y-118263D01*
X884389Y-117971D01*
X885918Y-116805D01*
X886791Y-115639D01*
G01X896649Y-118263D02*
Y-106597D01*
G01Y-109513D02*
X897523Y-108055D01*
X898833Y-106888D01*
X900579Y-106597D01*
X902107Y-106888D01*
X903418Y-108055D01*
X904073Y-110096D01*
Y-118263D01*
G01X914586Y-110388D02*
X921573D01*
X920918Y-108346D01*
X919826Y-107180D01*
X918298Y-106597D01*
X916769Y-106888D01*
X915459Y-107763D01*
X914586Y-109805D01*
X914149Y-111555D01*
Y-113305D01*
X914586Y-115055D01*
X915678Y-116805D01*
X916988Y-117971D01*
X918516Y-118263D01*
X920044Y-117680D01*
X921573Y-115930D01*
G01X932304Y-118263D02*
Y-106597D01*
G01Y-108930D02*
X933396Y-107763D01*
X934488Y-106888D01*
X936016Y-106597D01*
X937107Y-106888D01*
X938418Y-107763D01*
G01X806635Y17060D02*
Y29560D01*
X813765Y17060D01*
Y29560D01*
G01X822600Y17060D02*
X821670Y17268D01*
X820740Y18101D01*
X820120Y19560D01*
X819810Y21227D01*
X820120Y22893D01*
X820740Y24352D01*
X821670Y25185D01*
X822600Y25393D01*
X823530Y25185D01*
X824460Y24352D01*
X825080Y22893D01*
X825235Y21227D01*
X825080Y19560D01*
X824460Y18101D01*
X823530Y17268D01*
X822600Y17060D01*
G01X835000Y29560D02*
Y17060D01*
G01X832830Y25393D02*
X837170D01*
G01X845075Y22685D02*
X850035D01*
X849570Y24143D01*
X848795Y24977D01*
X847710Y25393D01*
X846625Y25185D01*
X845695Y24560D01*
X845075Y23102D01*
X844765Y21851D01*
Y20602D01*
X845075Y19352D01*
X845850Y18101D01*
X846780Y17268D01*
X847865Y17060D01*
X848950Y17477D01*
X850035Y18726D01*
G01X859800Y16643D02*
X859490Y16852D01*
Y17268D01*
X859800Y17477D01*
X860110Y17268D01*
Y16852D01*
X859800Y16643D01*
G01Y22268D02*
X859490Y22477D01*
Y22893D01*
X859800Y23102D01*
X860110Y22893D01*
Y22477D01*
X859800Y22268D01*
G01X869100Y17060D02*
Y29560D01*
X872975D01*
X874215Y28935D01*
X874990Y28102D01*
X875300Y26435D01*
X874990Y24768D01*
X874060Y23727D01*
X872975Y23102D01*
X869100D01*
G01X872975D02*
X875300Y17060D01*
G01X882275Y22685D02*
X887235D01*
X886770Y24143D01*
X885995Y24977D01*
X884910Y25393D01*
X883825Y25185D01*
X882895Y24560D01*
X882275Y23102D01*
X881965Y21851D01*
Y20602D01*
X882275Y19352D01*
X883050Y18101D01*
X883980Y17268D01*
X885065Y17060D01*
X886150Y17477D01*
X887235Y18726D01*
G01X896070Y17060D02*
Y27685D01*
X896380Y28726D01*
X897000Y29352D01*
X897930Y29560D01*
X898860Y29143D01*
X899325Y28102D01*
G01X897465Y24560D02*
X894365D01*
G01X907075Y22685D02*
X912035D01*
X911570Y24143D01*
X910795Y24977D01*
X909710Y25393D01*
X908625Y25185D01*
X907695Y24560D01*
X907075Y23102D01*
X906765Y21851D01*
Y20602D01*
X907075Y19352D01*
X907850Y18101D01*
X908780Y17268D01*
X909865Y17060D01*
X910950Y17477D01*
X912035Y18726D01*
G01X919630Y17060D02*
Y25393D01*
G01Y23727D02*
X920405Y24560D01*
X921180Y25185D01*
X922265Y25393D01*
X923040Y25185D01*
X923970Y24560D01*
G01X946600Y29560D02*
Y17060D01*
G01X944430Y25393D02*
X948770D01*
G01X959000Y17060D02*
X958070Y17268D01*
X957140Y18101D01*
X956520Y19560D01*
X956210Y21227D01*
X956520Y22893D01*
X957140Y24352D01*
X958070Y25185D01*
X959000Y25393D01*
X959930Y25185D01*
X960860Y24352D01*
X961480Y22893D01*
X961635Y21227D01*
X961480Y19560D01*
X960860Y18101D01*
X959930Y17268D01*
X959000Y17060D01*
G01X980390D02*
Y29560D01*
X983490D01*
X984730Y28935D01*
X985660Y28102D01*
X986435Y26852D01*
X987055Y25393D01*
X987210Y23310D01*
X987055Y21227D01*
X986435Y19768D01*
X985660Y18518D01*
X984730Y17685D01*
X983490Y17060D01*
X980390D01*
G01X993100D02*
Y29560D01*
X996975D01*
X998215Y28935D01*
X998990Y28102D01*
X999300Y26435D01*
X998990Y24768D01*
X998060Y23727D01*
X996975Y23102D01*
X993100D01*
G01X996975D02*
X999300Y17060D01*
G01X1006740Y29560D02*
X1010460D01*
G01X1008600D02*
Y17060D01*
G01X1006740D02*
X1010460D01*
G01X1017900Y29560D02*
Y17060D01*
X1024100D01*
G01X1030300Y29560D02*
Y17060D01*
X1036500D01*
G01X1058200D02*
Y29560D01*
G01X1073390Y17060D02*
Y25393D01*
G01Y23935D02*
X1072770Y24768D01*
X1071840Y25185D01*
X1070755Y25393D01*
X1069670Y24977D01*
X1068740Y24143D01*
X1068120Y22893D01*
X1067810Y21227D01*
X1068120Y19560D01*
X1068740Y18310D01*
X1069670Y17477D01*
X1070755Y17060D01*
X1071840Y17268D01*
X1072770Y17893D01*
X1073390Y18726D01*
G01X1079745Y13310D02*
X1080675Y12893D01*
X1081915Y13310D01*
X1082690Y14143D01*
X1083310Y15185D01*
X1084240Y18518D01*
X1086255Y25393D01*
G01X1081295D02*
X1084240Y18518D01*
G01X1093075Y22685D02*
X1098035D01*
X1097570Y24143D01*
X1096795Y24977D01*
X1095710Y25393D01*
X1094625Y25185D01*
X1093695Y24560D01*
X1093075Y23102D01*
X1092765Y21851D01*
Y20602D01*
X1093075Y19352D01*
X1093850Y18101D01*
X1094780Y17268D01*
X1095865Y17060D01*
X1096950Y17477D01*
X1098035Y18726D01*
G01X1105630Y17060D02*
Y25393D01*
G01Y23727D02*
X1106405Y24560D01*
X1107180Y25185D01*
X1108265Y25393D01*
X1109040Y25185D01*
X1109970Y24560D01*
G01X1131670Y17060D02*
Y27685D01*
X1131980Y28726D01*
X1132600Y29352D01*
X1133530Y29560D01*
X1134460Y29143D01*
X1134925Y28102D01*
G01X1133065Y24560D02*
X1129965D01*
G01X1145000Y17060D02*
X1144070Y17268D01*
X1143140Y18101D01*
X1142520Y19560D01*
X1142210Y21227D01*
X1142520Y22893D01*
X1143140Y24352D01*
X1144070Y25185D01*
X1145000Y25393D01*
X1145930Y25185D01*
X1146860Y24352D01*
X1147480Y22893D01*
X1147635Y21227D01*
X1147480Y19560D01*
X1146860Y18101D01*
X1145930Y17268D01*
X1145000Y17060D01*
G01X1155230D02*
Y25393D01*
G01Y23727D02*
X1156005Y24560D01*
X1156780Y25185D01*
X1157865Y25393D01*
X1158640Y25185D01*
X1159570Y24560D01*
G01X1185300Y17060D02*
X1179100D01*
Y29560D01*
X1185300D01*
G01X1182820Y23518D02*
X1179100D01*
G01X1191500Y29560D02*
Y17060D01*
X1197700D01*
G01X1203900Y29560D02*
Y17060D01*
X1210100D01*
G01X1217540Y29560D02*
X1221260D01*
G01X1219400D02*
Y17060D01*
G01X1217540D02*
X1221260D01*
G01X1228700D02*
Y29560D01*
X1232420D01*
X1233660Y28935D01*
X1234590Y27477D01*
X1234900Y25810D01*
X1234590Y24143D01*
X1233815Y22893D01*
X1232420Y22268D01*
X1228700D01*
G01X1240945Y18726D02*
X1242185Y17685D01*
X1243580Y17060D01*
X1244820D01*
X1246060Y17685D01*
X1246990Y18726D01*
X1247455Y20185D01*
X1247145Y21643D01*
X1246370Y22893D01*
X1244975Y23727D01*
X1243115Y24143D01*
X1242030Y24977D01*
X1241565Y26435D01*
X1241875Y27893D01*
X1242650Y28935D01*
X1243735Y29560D01*
X1244820D01*
X1245905Y29143D01*
X1246835Y28102D01*
G01X1259700Y17060D02*
X1253500D01*
Y29560D01*
X1259700D01*
G01X1257220Y23518D02*
X1253500D01*
G01X1284190Y29560D02*
Y17060D01*
G01Y18935D02*
X1283570Y17893D01*
X1282640Y17268D01*
X1281555Y17060D01*
X1280315Y17477D01*
X1279385Y18518D01*
X1278765Y19768D01*
X1278610Y21227D01*
X1278765Y22685D01*
X1279385Y23935D01*
X1280315Y24977D01*
X1281555Y25393D01*
X1282640Y25185D01*
X1283415Y24768D01*
X1284190Y23935D01*
G01X1291630Y17060D02*
Y25393D01*
G01Y23727D02*
X1292405Y24560D01*
X1293180Y25185D01*
X1294265Y25393D01*
X1295040Y25185D01*
X1295970Y24560D01*
G01X1306200Y25393D02*
Y17060D01*
G01Y28726D02*
X1305890Y28935D01*
Y29352D01*
X1306200Y29560D01*
X1306510Y29352D01*
Y28935D01*
X1306200Y28726D01*
G01X1318600Y17060D02*
Y29560D01*
G01X1331000Y17060D02*
Y29560D01*
G01X1358590D02*
Y17060D01*
G01Y18935D02*
X1357970Y17893D01*
X1357040Y17268D01*
X1355955Y17060D01*
X1354715Y17477D01*
X1353785Y18518D01*
X1353165Y19768D01*
X1353010Y21227D01*
X1353165Y22685D01*
X1353785Y23935D01*
X1354715Y24977D01*
X1355955Y25393D01*
X1357040Y25185D01*
X1357815Y24768D01*
X1358590Y23935D01*
G01X1368200Y25393D02*
Y17060D01*
G01Y28726D02*
X1367890Y28935D01*
Y29352D01*
X1368200Y29560D01*
X1368510Y29352D01*
Y28935D01*
X1368200Y28726D01*
G01X1378430Y17060D02*
Y25393D01*
G01Y23727D02*
X1379205Y24560D01*
X1379980Y25185D01*
X1381065Y25393D01*
X1381840Y25185D01*
X1382770Y24560D01*
G01X1390675Y22685D02*
X1395635D01*
X1395170Y24143D01*
X1394395Y24977D01*
X1393310Y25393D01*
X1392225Y25185D01*
X1391295Y24560D01*
X1390675Y23102D01*
X1390365Y21851D01*
Y20602D01*
X1390675Y19352D01*
X1391450Y18101D01*
X1392380Y17268D01*
X1393465Y17060D01*
X1394550Y17477D01*
X1395635Y18726D01*
G01X1407880Y24352D02*
X1406795Y25185D01*
X1405865Y25393D01*
X1404625Y24977D01*
X1403695Y24143D01*
X1403075Y22685D01*
X1402920Y21227D01*
X1403075Y19768D01*
X1403695Y18518D01*
X1404625Y17477D01*
X1405865Y17060D01*
X1406950Y17477D01*
X1407880Y18310D01*
G01X1417800Y29560D02*
Y17060D01*
G01X1415630Y25393D02*
X1419970D01*
G01X1430200D02*
Y17060D01*
G01Y28726D02*
X1429890Y28935D01*
Y29352D01*
X1430200Y29560D01*
X1430510Y29352D01*
Y28935D01*
X1430200Y28726D01*
G01X1442600Y17060D02*
X1441670Y17268D01*
X1440740Y18101D01*
X1440120Y19560D01*
X1439810Y21227D01*
X1440120Y22893D01*
X1440740Y24352D01*
X1441670Y25185D01*
X1442600Y25393D01*
X1443530Y25185D01*
X1444460Y24352D01*
X1445080Y22893D01*
X1445235Y21227D01*
X1445080Y19560D01*
X1444460Y18101D01*
X1443530Y17268D01*
X1442600Y17060D01*
G01X1452365D02*
Y25393D01*
G01Y23310D02*
X1452985Y24352D01*
X1453915Y25185D01*
X1455155Y25393D01*
X1456240Y25185D01*
X1457170Y24352D01*
X1457635Y22893D01*
Y17060D01*
G01X805550Y47060D02*
Y268760D01*
X1289150D01*
Y47060D01*
X805550D01*
G01Y75160D02*
X1289150D01*
G01X805550Y159460D02*
X1289150D01*
G01X805550Y131360D02*
X1289150D01*
G01X805550Y103260D02*
X1289150D01*
G01X816555Y196910D02*
Y209410D01*
X822445D01*
G01X820275Y203368D02*
X816555D01*
G01X830040Y209410D02*
X833760D01*
G01X831900D02*
Y196910D01*
G01X830040D02*
X833760D01*
G01X845230Y203160D02*
X848330D01*
Y199410D01*
X847400Y198160D01*
X846315Y197327D01*
X844765Y196910D01*
X843215Y197327D01*
X842130Y198160D01*
X841200Y199410D01*
X840580Y200868D01*
X840270Y202535D01*
Y203993D01*
X840580Y205243D01*
X841200Y206702D01*
X842130Y207952D01*
X843060Y208785D01*
X844300Y209410D01*
X845385D01*
X846625Y208993D01*
X847555Y208160D01*
G01X853290Y209410D02*
Y200452D01*
X853910Y198576D01*
X855150Y197327D01*
X856700Y196910D01*
X858250Y197327D01*
X859490Y198576D01*
X860110Y200452D01*
Y209410D01*
G01X866000Y196910D02*
Y209410D01*
X869875D01*
X871115Y208785D01*
X871890Y207952D01*
X872200Y206285D01*
X871890Y204618D01*
X870960Y203577D01*
X869875Y202952D01*
X866000D01*
G01X869875D02*
X872200Y196910D01*
G01X884600D02*
X878400D01*
Y209410D01*
X884600D01*
G01X882120Y203368D02*
X878400D01*
G01X805550Y215660D02*
X1289150D01*
G01X805550Y187560D02*
X1289150D01*
G01X805550Y243760D02*
X1289150D01*
G01X853991Y-145763D02*
X859231D01*
G01X856611D02*
Y-163263D01*
G01X853991D02*
X859231D01*
G01X868652Y-145763D02*
X874111Y-163263D01*
X879570Y-145763D01*
G01X891611Y-163263D02*
Y-155388D01*
X887244Y-145763D01*
G01X895978D02*
X891611Y-155388D01*
G01X895450Y215660D02*
Y47060D01*
G01X888940Y250010D02*
Y262510D01*
X892040D01*
X893280Y261885D01*
X894210Y261052D01*
X894985Y259802D01*
X895605Y258343D01*
X895760Y256260D01*
X895605Y254177D01*
X894985Y252718D01*
X894210Y251468D01*
X893280Y250635D01*
X892040Y250010D01*
X888940D01*
G01X901650D02*
Y262510D01*
X905525D01*
X906765Y261885D01*
X907540Y261052D01*
X907850Y259385D01*
X907540Y257718D01*
X906610Y256677D01*
X905525Y256052D01*
X901650D01*
G01X905525D02*
X907850Y250010D01*
G01X915290Y262510D02*
X919010D01*
G01X917150D02*
Y250010D01*
G01X915290D02*
X919010D01*
G01X926450Y262510D02*
Y250010D01*
X932650D01*
G01X938850Y262510D02*
Y250010D01*
X945050D01*
G01X970160Y261468D02*
X969230Y262093D01*
X968145Y262510D01*
X966905D01*
X965510Y261885D01*
X964425Y260843D01*
X963650Y259593D01*
X963030Y257510D01*
X962875Y255635D01*
X963185Y253760D01*
X963650Y252510D01*
X964580Y251260D01*
X965665Y250427D01*
X966750Y250010D01*
X967835D01*
X968920Y250427D01*
X969850Y251051D01*
X970625Y251885D01*
G01X975895Y250010D02*
Y262510D01*
G01X982405D02*
Y250010D01*
G01Y256260D02*
X975895D01*
G01X987675Y250010D02*
X991550Y262510D01*
X995425Y250010D01*
G01X994030Y254385D02*
X989070D01*
G01X1000850Y250010D02*
Y262510D01*
X1004725D01*
X1005965Y261885D01*
X1006740Y261052D01*
X1007050Y259385D01*
X1006740Y257718D01*
X1005810Y256677D01*
X1004725Y256052D01*
X1000850D01*
G01X1004725D02*
X1007050Y250010D01*
G01X1016350Y262510D02*
Y250010D01*
G01X1012785Y262510D02*
X1019915D01*
G01X1028750Y249593D02*
X1028440Y249802D01*
Y250218D01*
X1028750Y250427D01*
X1029060Y250218D01*
Y249802D01*
X1028750Y249593D01*
G01Y255218D02*
X1028440Y255427D01*
Y255843D01*
X1028750Y256052D01*
X1029060Y255843D01*
Y255427D01*
X1028750Y255218D01*
G01X1053550Y262510D02*
Y250010D01*
G01X1049985Y262510D02*
X1057115D01*
G01X1065950Y250010D02*
X1064710Y250218D01*
X1063625Y251051D01*
X1062695Y252302D01*
X1062075Y253760D01*
X1061765Y255427D01*
Y257093D01*
X1062075Y258760D01*
X1062695Y260218D01*
X1063625Y261468D01*
X1064710Y262302D01*
X1065950Y262510D01*
X1067190Y262302D01*
X1068275Y261468D01*
X1069205Y260218D01*
X1069825Y258760D01*
X1070135Y257093D01*
Y255427D01*
X1069825Y253760D01*
X1069205Y252302D01*
X1068275Y251051D01*
X1067190Y250218D01*
X1065950Y250010D01*
G01X1075250D02*
Y262510D01*
X1078970D01*
X1080210Y261885D01*
X1081140Y260427D01*
X1081450Y258760D01*
X1081140Y257093D01*
X1080365Y255843D01*
X1078970Y255218D01*
X1075250D01*
G01X1103150Y262510D02*
Y250010D01*
G01X1100980Y258343D02*
X1105320D01*
G01X1115550Y250010D02*
X1114620Y250218D01*
X1113690Y251051D01*
X1113070Y252510D01*
X1112760Y254177D01*
X1113070Y255843D01*
X1113690Y257302D01*
X1114620Y258135D01*
X1115550Y258343D01*
X1116480Y258135D01*
X1117410Y257302D01*
X1118030Y255843D01*
X1118185Y254177D01*
X1118030Y252510D01*
X1117410Y251051D01*
X1116480Y250218D01*
X1115550Y250010D01*
G01X1141590Y256677D02*
X1142210Y257302D01*
X1142675Y258343D01*
X1142985Y259802D01*
X1142675Y261052D01*
X1142055Y261885D01*
X1140970Y262510D01*
X1136785D01*
Y250010D01*
X1141900D01*
X1142985Y250843D01*
X1143605Y252093D01*
X1143915Y253552D01*
X1143605Y255010D01*
X1142675Y256260D01*
X1141590Y256677D01*
X1136785D01*
G01X1152750Y250010D02*
X1151510Y250218D01*
X1150425Y251051D01*
X1149495Y252302D01*
X1148875Y253760D01*
X1148565Y255427D01*
Y257093D01*
X1148875Y258760D01*
X1149495Y260218D01*
X1150425Y261468D01*
X1151510Y262302D01*
X1152750Y262510D01*
X1153990Y262302D01*
X1155075Y261468D01*
X1156005Y260218D01*
X1156625Y258760D01*
X1156935Y257093D01*
Y255427D01*
X1156625Y253760D01*
X1156005Y252302D01*
X1155075Y251051D01*
X1153990Y250218D01*
X1152750Y250010D01*
G01X1165150Y262510D02*
Y250010D01*
G01X1161585Y262510D02*
X1168715D01*
G01X1177550D02*
Y250010D01*
G01X1173985Y262510D02*
X1181115D01*
G01X1189950Y250010D02*
X1188710Y250218D01*
X1187625Y251051D01*
X1186695Y252302D01*
X1186075Y253760D01*
X1185765Y255427D01*
Y257093D01*
X1186075Y258760D01*
X1186695Y260218D01*
X1187625Y261468D01*
X1188710Y262302D01*
X1189950Y262510D01*
X1191190Y262302D01*
X1192275Y261468D01*
X1193205Y260218D01*
X1193825Y258760D01*
X1194135Y257093D01*
Y255427D01*
X1193825Y253760D01*
X1193205Y252302D01*
X1192275Y251051D01*
X1191190Y250218D01*
X1189950Y250010D01*
G01X1198320D02*
Y262510D01*
X1202350Y252093D01*
X1206380Y262510D01*
Y250010D01*
G01X919475Y225010D02*
X923350Y237510D01*
X927225Y225010D01*
G01X925830Y229385D02*
X920870D01*
G01X932650Y237510D02*
Y225010D01*
X938850D01*
G01X945050Y237510D02*
Y225010D01*
X951250D01*
G01X969540Y237510D02*
Y228552D01*
X970160Y226676D01*
X971400Y225427D01*
X972950Y225010D01*
X974500Y225427D01*
X975740Y226676D01*
X976360Y228552D01*
Y237510D01*
G01X981785Y225010D02*
Y237510D01*
X988915Y225010D01*
Y237510D01*
G01X995890D02*
X999610D01*
G01X997750D02*
Y225010D01*
G01X995890D02*
X999610D01*
G01X1010150Y237510D02*
Y225010D01*
G01X1006585Y237510D02*
X1013715D01*
G01X1019295Y226676D02*
X1020535Y225635D01*
X1021930Y225010D01*
X1023170D01*
X1024410Y225635D01*
X1025340Y226676D01*
X1025805Y228135D01*
X1025495Y229593D01*
X1024720Y230843D01*
X1023325Y231677D01*
X1021465Y232093D01*
X1020380Y232927D01*
X1019915Y234385D01*
X1020225Y235843D01*
X1021000Y236885D01*
X1022085Y237510D01*
X1023170D01*
X1024255Y237093D01*
X1025185Y236052D01*
G01X1043475Y225010D02*
X1047350Y237510D01*
X1051225Y225010D01*
G01X1049830Y229385D02*
X1044870D01*
G01X1056650Y225010D02*
Y237510D01*
X1060525D01*
X1061765Y236885D01*
X1062540Y236052D01*
X1062850Y234385D01*
X1062540Y232718D01*
X1061610Y231677D01*
X1060525Y231052D01*
X1056650D01*
G01X1060525D02*
X1062850Y225010D01*
G01X1075250D02*
X1069050D01*
Y237510D01*
X1075250D01*
G01X1072770Y231468D02*
X1069050D01*
G01X1095090Y237510D02*
X1098810D01*
G01X1096950D02*
Y225010D01*
G01X1095090D02*
X1098810D01*
G01X1105785D02*
Y237510D01*
X1112915Y225010D01*
Y237510D01*
G01X1130120Y225010D02*
Y237510D01*
X1134150Y227093D01*
X1138180Y237510D01*
Y225010D01*
G01X1144690Y237510D02*
X1148410D01*
G01X1146550D02*
Y225010D01*
G01X1144690D02*
X1148410D01*
G01X1155850Y237510D02*
Y225010D01*
X1162050D01*
G01X1168095Y226676D02*
X1169335Y225635D01*
X1170730Y225010D01*
X1171970D01*
X1173210Y225635D01*
X1174140Y226676D01*
X1174605Y228135D01*
X1174295Y229593D01*
X1173520Y230843D01*
X1172125Y231677D01*
X1170265Y232093D01*
X1169180Y232927D01*
X1168715Y234385D01*
X1169025Y235843D01*
X1169800Y236885D01*
X1170885Y237510D01*
X1171970D01*
X1173055Y237093D01*
X1173985Y236052D01*
G01X979061Y-163263D02*
Y-145763D01*
X976441Y-149263D01*
G01Y-163263D02*
X981681D01*
G01X996561D02*
Y-145763D01*
X993941Y-149263D01*
G01Y-163263D02*
X999181D01*
G01X1010131Y-163846D02*
X1017991Y-145763D01*
G01X1027413Y-148680D02*
X1028723Y-146930D01*
X1030251Y-146055D01*
X1031998Y-145763D01*
X1034181Y-146346D01*
X1035709Y-147805D01*
X1036146Y-149554D01*
X1035928Y-151305D01*
X1035054Y-152763D01*
X1030688Y-155680D01*
X1028723Y-157721D01*
X1027413Y-160639D01*
X1026976Y-163263D01*
X1036146D01*
G01X1044913Y-148680D02*
X1046223Y-146930D01*
X1047751Y-146055D01*
X1049498Y-145763D01*
X1051681Y-146346D01*
X1053209Y-147805D01*
X1053646Y-149554D01*
X1053428Y-151305D01*
X1052554Y-152763D01*
X1048188Y-155680D01*
X1046223Y-157721D01*
X1044913Y-160639D01*
X1044476Y-163263D01*
X1053646D01*
G01X1062631Y-163846D02*
X1070491Y-145763D01*
G01X1079913Y-148680D02*
X1081223Y-146930D01*
X1082751Y-146055D01*
X1084498Y-145763D01*
X1086681Y-146346D01*
X1088209Y-147805D01*
X1088646Y-149554D01*
X1088428Y-151305D01*
X1087554Y-152763D01*
X1083188Y-155680D01*
X1081223Y-157721D01*
X1079913Y-160639D01*
X1079476Y-163263D01*
X1088646D01*
G01X1101561Y-145763D02*
X1099814Y-146346D01*
X1098504Y-147805D01*
X1097631Y-149554D01*
X1096976Y-151888D01*
X1096758Y-154513D01*
X1096976Y-157138D01*
X1097631Y-159472D01*
X1098504Y-161222D01*
X1099814Y-162680D01*
X1101561Y-163263D01*
X1103307Y-162680D01*
X1104618Y-161222D01*
X1105491Y-159472D01*
X1106146Y-157138D01*
X1106364Y-154513D01*
X1106146Y-151888D01*
X1105491Y-149554D01*
X1104618Y-147805D01*
X1103307Y-146346D01*
X1101561Y-145763D01*
G01X1119061Y-163263D02*
Y-145763D01*
X1116441Y-149263D01*
G01Y-163263D02*
X1121681D01*
G01X1131758Y-159763D02*
X1133067Y-161805D01*
X1134814Y-162971D01*
X1136779Y-163263D01*
X1138526Y-162971D01*
X1140273Y-161513D01*
X1141364Y-159763D01*
X1141583Y-158013D01*
X1141146Y-155972D01*
X1139618Y-154513D01*
X1138089Y-153930D01*
X1136124D01*
G01X1138089D02*
X1139399Y-153055D01*
X1140491Y-151597D01*
X1140928Y-149847D01*
X1140491Y-148096D01*
X1139399Y-146638D01*
X1137434Y-145763D01*
X1135469Y-146055D01*
X1133504Y-147222D01*
G01X971400Y82960D02*
X972485Y83168D01*
X973725Y83793D01*
X974500Y84835D01*
X974810Y86293D01*
X974500Y87751D01*
X973570Y89002D01*
X972175Y89627D01*
X970625D01*
X969695Y90043D01*
X968920Y91085D01*
X968610Y92543D01*
X969075Y94002D01*
X970160Y95043D01*
X971400Y95460D01*
X972640Y95043D01*
X973725Y94002D01*
X974190Y92543D01*
X973880Y91085D01*
X973105Y90043D01*
X972175Y89627D01*
X970625D01*
X969230Y89002D01*
X968300Y87751D01*
X967990Y86293D01*
X968300Y84835D01*
X969075Y83793D01*
X970315Y83168D01*
X971400Y82960D01*
G01X980855Y88168D02*
X981940Y89627D01*
X982870Y90460D01*
X984110Y90877D01*
X985195Y90460D01*
X985970Y89627D01*
X986590Y88377D01*
X986745Y86918D01*
X986590Y85668D01*
X985970Y84418D01*
X985040Y83377D01*
X983955Y82960D01*
X982715Y83377D01*
X981630Y84626D01*
X981010Y86502D01*
X980855Y88585D01*
X981165Y91293D01*
X981630Y92752D01*
X982405Y94210D01*
X983490Y95252D01*
X984575Y95460D01*
X985660Y95043D01*
X986435Y94002D01*
G01X996200Y82543D02*
X995890Y82752D01*
Y83168D01*
X996200Y83377D01*
X996510Y83168D01*
Y82752D01*
X996200Y82543D01*
G01X1008600Y95460D02*
X1007360Y95043D01*
X1006430Y94002D01*
X1005810Y92752D01*
X1005345Y91085D01*
X1005190Y89210D01*
X1005345Y87335D01*
X1005810Y85668D01*
X1006430Y84418D01*
X1007360Y83377D01*
X1008600Y82960D01*
X1009840Y83377D01*
X1010770Y84418D01*
X1011390Y85668D01*
X1011855Y87335D01*
X1012010Y89210D01*
X1011855Y91085D01*
X1011390Y92752D01*
X1010770Y94002D01*
X1009840Y95043D01*
X1008600Y95460D01*
G01X968765Y56318D02*
X969850Y55277D01*
X971090Y54860D01*
X972330Y55277D01*
X973415Y56526D01*
X974190Y58402D01*
X974500Y60277D01*
Y62568D01*
X974190Y64443D01*
X973415Y66110D01*
X972485Y66943D01*
X971400Y67360D01*
X970160Y66943D01*
X969230Y66110D01*
X968610Y64860D01*
X968300Y63193D01*
X968610Y61735D01*
X969385Y60277D01*
X970315Y59443D01*
X971400Y59235D01*
X972640Y59651D01*
X973570Y60693D01*
X974500Y62568D01*
G01X980390Y57360D02*
X981320Y55901D01*
X982560Y55068D01*
X983955Y54860D01*
X985195Y55068D01*
X986435Y56110D01*
X987210Y57360D01*
X987365Y58610D01*
X987055Y60068D01*
X985970Y61110D01*
X984885Y61527D01*
X983490D01*
G01X984885D02*
X985815Y62152D01*
X986590Y63193D01*
X986900Y64443D01*
X986590Y65693D01*
X985815Y66735D01*
X984420Y67360D01*
X983025Y67152D01*
X981630Y66318D01*
G01X996200Y54443D02*
X995890Y54652D01*
Y55068D01*
X996200Y55277D01*
X996510Y55068D01*
Y54652D01*
X996200Y54443D01*
G01X1008600Y67360D02*
X1007360Y66943D01*
X1006430Y65902D01*
X1005810Y64652D01*
X1005345Y62985D01*
X1005190Y61110D01*
X1005345Y59235D01*
X1005810Y57568D01*
X1006430Y56318D01*
X1007360Y55277D01*
X1008600Y54860D01*
X1009840Y55277D01*
X1010770Y56318D01*
X1011390Y57568D01*
X1011855Y59235D01*
X1012010Y61110D01*
X1011855Y62985D01*
X1011390Y64652D01*
X1010770Y65902D01*
X1009840Y66943D01*
X1008600Y67360D01*
G01X971400Y167260D02*
Y179760D01*
X969540Y177260D01*
G01Y167260D02*
X973260D01*
G01X980855Y177677D02*
X981785Y178926D01*
X982870Y179552D01*
X984110Y179760D01*
X985660Y179343D01*
X986745Y178302D01*
X987055Y177052D01*
X986900Y175801D01*
X986280Y174760D01*
X983180Y172677D01*
X981785Y171218D01*
X980855Y169135D01*
X980545Y167260D01*
X987055D01*
G01X996200Y166843D02*
X995890Y167052D01*
Y167468D01*
X996200Y167677D01*
X996510Y167468D01*
Y167052D01*
X996200Y166843D01*
G01X1008600Y179760D02*
X1007360Y179343D01*
X1006430Y178302D01*
X1005810Y177052D01*
X1005345Y175385D01*
X1005190Y173510D01*
X1005345Y171635D01*
X1005810Y169968D01*
X1006430Y168718D01*
X1007360Y167677D01*
X1008600Y167260D01*
X1009840Y167677D01*
X1010770Y168718D01*
X1011390Y169968D01*
X1011855Y171635D01*
X1012010Y173510D01*
X1011855Y175385D01*
X1011390Y177052D01*
X1010770Y178302D01*
X1009840Y179343D01*
X1008600Y179760D01*
G01X971400Y139160D02*
Y151660D01*
X969540Y149160D01*
G01Y139160D02*
X973260D01*
G01X980855Y144368D02*
X981940Y145827D01*
X982870Y146660D01*
X984110Y147077D01*
X985195Y146660D01*
X985970Y145827D01*
X986590Y144577D01*
X986745Y143118D01*
X986590Y141868D01*
X985970Y140618D01*
X985040Y139577D01*
X983955Y139160D01*
X982715Y139577D01*
X981630Y140826D01*
X981010Y142702D01*
X980855Y144785D01*
X981165Y147493D01*
X981630Y148952D01*
X982405Y150410D01*
X983490Y151452D01*
X984575Y151660D01*
X985660Y151243D01*
X986435Y150202D01*
G01X996200Y138743D02*
X995890Y138952D01*
Y139368D01*
X996200Y139577D01*
X996510Y139368D01*
Y138952D01*
X996200Y138743D01*
G01X1008600Y151660D02*
X1007360Y151243D01*
X1006430Y150202D01*
X1005810Y148952D01*
X1005345Y147285D01*
X1005190Y145410D01*
X1005345Y143535D01*
X1005810Y141868D01*
X1006430Y140618D01*
X1007360Y139577D01*
X1008600Y139160D01*
X1009840Y139577D01*
X1010770Y140618D01*
X1011390Y141868D01*
X1011855Y143535D01*
X1012010Y145410D01*
X1011855Y147285D01*
X1011390Y148952D01*
X1010770Y150202D01*
X1009840Y151243D01*
X1008600Y151660D01*
G01X968455Y121477D02*
X969385Y122726D01*
X970470Y123352D01*
X971710Y123560D01*
X973260Y123143D01*
X974345Y122102D01*
X974655Y120852D01*
X974500Y119601D01*
X973880Y118560D01*
X970780Y116477D01*
X969385Y115018D01*
X968455Y112935D01*
X968145Y111060D01*
X974655D01*
G01X981165Y112518D02*
X982250Y111477D01*
X983490Y111060D01*
X984730Y111477D01*
X985815Y112726D01*
X986590Y114602D01*
X986900Y116477D01*
Y118768D01*
X986590Y120643D01*
X985815Y122310D01*
X984885Y123143D01*
X983800Y123560D01*
X982560Y123143D01*
X981630Y122310D01*
X981010Y121060D01*
X980700Y119393D01*
X981010Y117935D01*
X981785Y116477D01*
X982715Y115643D01*
X983800Y115435D01*
X985040Y115851D01*
X985970Y116893D01*
X986900Y118768D01*
G01X996200Y110643D02*
X995890Y110852D01*
Y111268D01*
X996200Y111477D01*
X996510Y111268D01*
Y110852D01*
X996200Y110643D01*
G01X1008600Y123560D02*
X1007360Y123143D01*
X1006430Y122102D01*
X1005810Y120852D01*
X1005345Y119185D01*
X1005190Y117310D01*
X1005345Y115435D01*
X1005810Y113768D01*
X1006430Y112518D01*
X1007360Y111477D01*
X1008600Y111060D01*
X1009840Y111477D01*
X1010770Y112518D01*
X1011390Y113768D01*
X1011855Y115435D01*
X1012010Y117310D01*
X1011855Y119185D01*
X1011390Y120852D01*
X1010770Y122102D01*
X1009840Y123143D01*
X1008600Y123560D01*
G01X968145Y198576D02*
X969385Y197535D01*
X970780Y196910D01*
X972020D01*
X973260Y197535D01*
X974190Y198576D01*
X974655Y200035D01*
X974345Y201493D01*
X973570Y202743D01*
X972175Y203577D01*
X970315Y203993D01*
X969230Y204827D01*
X968765Y206285D01*
X969075Y207743D01*
X969850Y208785D01*
X970935Y209410D01*
X972020D01*
X973105Y208993D01*
X974035Y207952D01*
G01X981940Y209410D02*
X985660D01*
G01X983800D02*
Y196910D01*
G01X981940D02*
X985660D01*
G01X993255Y209410D02*
X999145D01*
X993255Y196910D01*
X999145D01*
G01X1011700D02*
X1005500D01*
Y209410D01*
X1011700D01*
G01X1009220Y203368D02*
X1005500D01*
G01X1026758Y-118263D02*
Y-100763D01*
X1031124D01*
X1032871Y-101638D01*
X1034181Y-102805D01*
X1035273Y-104554D01*
X1036146Y-106597D01*
X1036364Y-109513D01*
X1036146Y-112430D01*
X1035273Y-114472D01*
X1034181Y-116222D01*
X1032871Y-117388D01*
X1031124Y-118263D01*
X1026758D01*
G01X1052991D02*
Y-106597D01*
G01Y-108638D02*
X1052118Y-107472D01*
X1050807Y-106888D01*
X1049279Y-106597D01*
X1047751Y-107180D01*
X1046441Y-108346D01*
X1045567Y-110096D01*
X1045131Y-112430D01*
X1045567Y-114763D01*
X1046441Y-116513D01*
X1047751Y-117680D01*
X1049279Y-118263D01*
X1050807Y-117971D01*
X1052118Y-117097D01*
X1052991Y-115930D01*
G01X1066561Y-100763D02*
Y-118263D01*
G01X1063504Y-106597D02*
X1069618D01*
G01X1080786Y-110388D02*
X1087773D01*
X1087118Y-108346D01*
X1086026Y-107180D01*
X1084498Y-106597D01*
X1082969Y-106888D01*
X1081659Y-107763D01*
X1080786Y-109805D01*
X1080349Y-111555D01*
Y-113305D01*
X1080786Y-115055D01*
X1081878Y-116805D01*
X1083188Y-117971D01*
X1084716Y-118263D01*
X1086244Y-117680D01*
X1087773Y-115930D01*
G01X1088735Y82960D02*
Y95460D01*
X1095865Y82960D01*
Y95460D01*
G01X1104700Y82960D02*
X1103460Y83168D01*
X1102375Y84001D01*
X1101445Y85252D01*
X1100825Y86710D01*
X1100515Y88377D01*
Y90043D01*
X1100825Y91710D01*
X1101445Y93168D01*
X1102375Y94418D01*
X1103460Y95252D01*
X1104700Y95460D01*
X1105940Y95252D01*
X1107025Y94418D01*
X1107955Y93168D01*
X1108575Y91710D01*
X1108885Y90043D01*
Y88377D01*
X1108575Y86710D01*
X1107955Y85252D01*
X1107025Y84001D01*
X1105940Y83168D01*
X1104700Y82960D01*
G01X1113535D02*
Y95460D01*
X1120665Y82960D01*
Y95460D01*
G01X1127485Y87127D02*
X1131515D01*
G01X1138800Y82960D02*
Y95460D01*
X1142520D01*
X1143760Y94835D01*
X1144690Y93377D01*
X1145000Y91710D01*
X1144690Y90043D01*
X1143915Y88793D01*
X1142520Y88168D01*
X1138800D01*
G01X1151200Y95460D02*
Y82960D01*
X1157400D01*
G01X1162825D02*
X1166700Y95460D01*
X1170575Y82960D01*
G01X1169180Y87335D02*
X1164220D01*
G01X1179100Y95460D02*
Y82960D01*
G01X1175535Y95460D02*
X1182665D01*
G01X1194600Y82960D02*
X1188400D01*
Y95460D01*
X1194600D01*
G01X1192120Y89418D02*
X1188400D01*
G01X1200490Y82960D02*
Y95460D01*
X1203590D01*
X1204830Y94835D01*
X1205760Y94002D01*
X1206535Y92752D01*
X1207155Y91293D01*
X1207310Y89210D01*
X1207155Y87127D01*
X1206535Y85668D01*
X1205760Y84418D01*
X1204830Y83585D01*
X1203590Y82960D01*
X1200490D01*
G01X1088735Y54860D02*
Y67360D01*
X1095865Y54860D01*
Y67360D01*
G01X1104700Y54860D02*
X1103460Y55068D01*
X1102375Y55901D01*
X1101445Y57152D01*
X1100825Y58610D01*
X1100515Y60277D01*
Y61943D01*
X1100825Y63610D01*
X1101445Y65068D01*
X1102375Y66318D01*
X1103460Y67152D01*
X1104700Y67360D01*
X1105940Y67152D01*
X1107025Y66318D01*
X1107955Y65068D01*
X1108575Y63610D01*
X1108885Y61943D01*
Y60277D01*
X1108575Y58610D01*
X1107955Y57152D01*
X1107025Y55901D01*
X1105940Y55068D01*
X1104700Y54860D01*
G01X1113535D02*
Y67360D01*
X1120665Y54860D01*
Y67360D01*
G01X1127485Y59027D02*
X1131515D01*
G01X1138800Y54860D02*
Y67360D01*
X1142520D01*
X1143760Y66735D01*
X1144690Y65277D01*
X1145000Y63610D01*
X1144690Y61943D01*
X1143915Y60693D01*
X1142520Y60068D01*
X1138800D01*
G01X1151200Y67360D02*
Y54860D01*
X1157400D01*
G01X1162825D02*
X1166700Y67360D01*
X1170575Y54860D01*
G01X1169180Y59235D02*
X1164220D01*
G01X1179100Y67360D02*
Y54860D01*
G01X1175535Y67360D02*
X1182665D01*
G01X1194600Y54860D02*
X1188400D01*
Y67360D01*
X1194600D01*
G01X1192120Y61318D02*
X1188400D01*
G01X1200490Y54860D02*
Y67360D01*
X1203590D01*
X1204830Y66735D01*
X1205760Y65902D01*
X1206535Y64652D01*
X1207155Y63193D01*
X1207310Y61110D01*
X1207155Y59027D01*
X1206535Y57568D01*
X1205760Y56318D01*
X1204830Y55485D01*
X1203590Y54860D01*
X1200490D01*
G01X1084550Y215660D02*
Y47060D01*
G01X1114000Y167260D02*
Y179760D01*
X1117720D01*
X1118960Y179135D01*
X1119890Y177677D01*
X1120200Y176010D01*
X1119890Y174343D01*
X1119115Y173093D01*
X1117720Y172468D01*
X1114000D01*
G01X1126400Y179760D02*
Y167260D01*
X1132600D01*
G01X1138025D02*
X1141900Y179760D01*
X1145775Y167260D01*
G01X1144380Y171635D02*
X1139420D01*
G01X1154300Y179760D02*
Y167260D01*
G01X1150735Y179760D02*
X1157865D01*
G01X1169800Y167260D02*
X1163600D01*
Y179760D01*
X1169800D01*
G01X1167320Y173718D02*
X1163600D01*
G01X1175690Y167260D02*
Y179760D01*
X1178790D01*
X1180030Y179135D01*
X1180960Y178302D01*
X1181735Y177052D01*
X1182355Y175593D01*
X1182510Y173510D01*
X1182355Y171427D01*
X1181735Y169968D01*
X1180960Y168718D01*
X1180030Y167885D01*
X1178790Y167260D01*
X1175690D01*
G01X1114000Y139160D02*
Y151660D01*
X1117720D01*
X1118960Y151035D01*
X1119890Y149577D01*
X1120200Y147910D01*
X1119890Y146243D01*
X1119115Y144993D01*
X1117720Y144368D01*
X1114000D01*
G01X1126400Y151660D02*
Y139160D01*
X1132600D01*
G01X1138025D02*
X1141900Y151660D01*
X1145775Y139160D01*
G01X1144380Y143535D02*
X1139420D01*
G01X1154300Y151660D02*
Y139160D01*
G01X1150735Y151660D02*
X1157865D01*
G01X1169800Y139160D02*
X1163600D01*
Y151660D01*
X1169800D01*
G01X1167320Y145618D02*
X1163600D01*
G01X1175690Y139160D02*
Y151660D01*
X1178790D01*
X1180030Y151035D01*
X1180960Y150202D01*
X1181735Y148952D01*
X1182355Y147493D01*
X1182510Y145410D01*
X1182355Y143327D01*
X1181735Y141868D01*
X1180960Y140618D01*
X1180030Y139785D01*
X1178790Y139160D01*
X1175690D01*
G01X1114000Y111060D02*
Y123560D01*
X1117720D01*
X1118960Y122935D01*
X1119890Y121477D01*
X1120200Y119810D01*
X1119890Y118143D01*
X1119115Y116893D01*
X1117720Y116268D01*
X1114000D01*
G01X1126400Y123560D02*
Y111060D01*
X1132600D01*
G01X1138025D02*
X1141900Y123560D01*
X1145775Y111060D01*
G01X1144380Y115435D02*
X1139420D01*
G01X1154300Y123560D02*
Y111060D01*
G01X1150735Y123560D02*
X1157865D01*
G01X1169800Y111060D02*
X1163600D01*
Y123560D01*
X1169800D01*
G01X1167320Y117518D02*
X1163600D01*
G01X1175690Y111060D02*
Y123560D01*
X1178790D01*
X1180030Y122935D01*
X1180960Y122102D01*
X1181735Y120852D01*
X1182355Y119393D01*
X1182510Y117310D01*
X1182355Y115227D01*
X1181735Y113768D01*
X1180960Y112518D01*
X1180030Y111685D01*
X1178790Y111060D01*
X1175690D01*
G01X1114000Y196910D02*
Y209410D01*
X1117720D01*
X1118960Y208785D01*
X1119890Y207327D01*
X1120200Y205660D01*
X1119890Y203993D01*
X1119115Y202743D01*
X1117720Y202118D01*
X1114000D01*
G01X1126400Y209410D02*
Y196910D01*
X1132600D01*
G01X1138025D02*
X1141900Y209410D01*
X1145775Y196910D01*
G01X1144380Y201285D02*
X1139420D01*
G01X1154300Y209410D02*
Y196910D01*
G01X1150735Y209410D02*
X1157865D01*
G01X1169800Y196910D02*
X1163600D01*
Y209410D01*
X1169800D01*
G01X1167320Y203368D02*
X1163600D01*
G01X1175690Y196910D02*
Y209410D01*
X1178790D01*
X1180030Y208785D01*
X1180960Y207952D01*
X1181735Y206702D01*
X1182355Y205243D01*
X1182510Y203160D01*
X1182355Y201077D01*
X1181735Y199618D01*
X1180960Y198368D01*
X1180030Y197535D01*
X1178790Y196910D01*
X1175690D01*
G01X1247455Y88168D02*
X1248540Y89627D01*
X1249470Y90460D01*
X1250710Y90877D01*
X1251795Y90460D01*
X1252570Y89627D01*
X1253190Y88377D01*
X1253345Y86918D01*
X1253190Y85668D01*
X1252570Y84418D01*
X1251640Y83377D01*
X1250555Y82960D01*
X1249315Y83377D01*
X1248230Y84626D01*
X1247610Y86502D01*
X1247455Y88585D01*
X1247765Y91293D01*
X1248230Y92752D01*
X1249005Y94210D01*
X1250090Y95252D01*
X1251175Y95460D01*
X1252260Y95043D01*
X1253035Y94002D01*
G01X1247455Y65277D02*
X1248385Y66526D01*
X1249470Y67152D01*
X1250710Y67360D01*
X1252260Y66943D01*
X1253345Y65902D01*
X1253655Y64652D01*
X1253500Y63401D01*
X1252880Y62360D01*
X1249780Y60277D01*
X1248385Y58818D01*
X1247455Y56735D01*
X1247145Y54860D01*
X1253655D01*
G01X1211650Y215660D02*
Y47060D01*
G01X1240790Y169760D02*
X1241720Y168301D01*
X1242960Y167468D01*
X1244355Y167260D01*
X1245595Y167468D01*
X1246835Y168510D01*
X1247610Y169760D01*
X1247765Y171010D01*
X1247455Y172468D01*
X1246370Y173510D01*
X1245285Y173927D01*
X1243890D01*
G01X1245285D02*
X1246215Y174552D01*
X1246990Y175593D01*
X1247300Y176843D01*
X1246990Y178093D01*
X1246215Y179135D01*
X1244820Y179760D01*
X1243425Y179552D01*
X1242030Y178718D01*
G01X1256290Y167260D02*
X1256600Y169968D01*
X1257065Y172260D01*
X1257685Y174343D01*
X1258460Y176635D01*
X1259700Y179760D01*
X1253500D01*
G01X1244200Y139160D02*
Y151660D01*
X1242340Y149160D01*
G01Y139160D02*
X1246060D01*
G01X1256290D02*
X1256600Y141868D01*
X1257065Y144160D01*
X1257685Y146243D01*
X1258460Y148535D01*
X1259700Y151660D01*
X1253500D01*
G01X1238000Y111060D02*
Y123560D01*
X1236140Y121060D01*
G01Y111060D02*
X1239860D01*
G01X1247455Y116268D02*
X1248540Y117727D01*
X1249470Y118560D01*
X1250710Y118977D01*
X1251795Y118560D01*
X1252570Y117727D01*
X1253190Y116477D01*
X1253345Y115018D01*
X1253190Y113768D01*
X1252570Y112518D01*
X1251640Y111477D01*
X1250555Y111060D01*
X1249315Y111477D01*
X1248230Y112726D01*
X1247610Y114602D01*
X1247455Y116685D01*
X1247765Y119393D01*
X1248230Y120852D01*
X1249005Y122310D01*
X1250090Y123352D01*
X1251175Y123560D01*
X1252260Y123143D01*
X1253035Y122102D01*
G01X1264660Y111060D02*
Y123560D01*
X1258925Y114602D01*
X1266675D01*
G01X1238000Y196910D02*
X1236760Y197118D01*
X1235675Y197951D01*
X1234745Y199202D01*
X1234125Y200660D01*
X1233815Y202327D01*
Y203993D01*
X1234125Y205660D01*
X1234745Y207118D01*
X1235675Y208368D01*
X1236760Y209202D01*
X1238000Y209410D01*
X1239240Y209202D01*
X1240325Y208368D01*
X1241255Y207118D01*
X1241875Y205660D01*
X1242185Y203993D01*
Y202327D01*
X1241875Y200660D01*
X1241255Y199202D01*
X1240325Y197951D01*
X1239240Y197118D01*
X1238000Y196910D01*
G01X1239240Y200243D02*
X1241100Y196910D01*
G01X1250400Y209410D02*
Y196910D01*
G01X1246835Y209410D02*
X1253965D01*
G01X1262800Y196910D02*
Y202535D01*
X1259700Y209410D01*
G01X1265900D02*
X1262800Y202535D01*
G01X-20271Y15000D02*
Y676339D01*
G01Y15000D02*
G03X-5271Y0I15000J0D01*
G01Y691339D02*
G03X-20271Y676339I0J-15000D01*
G01X0Y37795D02*
G03X3937Y33858I3937J0D01*
G01X21063Y29921D02*
G03X17126Y33858I-3937J0D01*
G01X3937D02*
X17126D01*
G01X299409Y0D02*
X23031D01*
G01X21063Y1969D02*
X23031Y0D01*
G01X21063Y1969D02*
Y29921D01*
G01X0Y102756D02*
Y37795D01*
G01D02*
G03X-7874I-3937J0D01*
G01X3937Y25984D02*
X13189D01*
G01X-7874Y37795D02*
G03X3937Y25984I11811J0D01*
G01X13189Y0D02*
X-5271D01*
G01X13189Y25984D02*
Y0D01*
G01X3937Y106693D02*
G03X0Y102756I0J-3937D01*
G01X-7874Y68504D02*
G03X0I3937J0D01*
G01X-7874D02*
Y122737D01*
G01X0Y118504D02*
G03X3937Y114567I3937J0D01*
G01Y157382D02*
G03X0Y153445I0J-3937D01*
G01X17126Y157382D02*
G03X21063Y161319I0J3937D01*
G01X0Y118504D02*
Y153445D01*
G01X21063Y219292D02*
Y161319D01*
G01D02*
Y187402D01*
G01X143701Y114567D02*
X3937D01*
G01Y157382D02*
X17126D01*
G01X3937Y106693D02*
X143701D01*
G01X-7874Y153445D02*
Y157382D01*
G01Y153445D02*
G03X0I3937J0D01*
G01Y122737D02*
G03X-7874I-3937J0D01*
G01X-10433Y161070D02*
G03X-7874Y157382I3937J0D01*
G01X-10433Y265210D02*
Y161070D01*
G01X51378Y181496D02*
G03X47441Y177559I0J-3937D01*
G01Y165748D02*
G03X51378Y161811I3937J0D01*
G01X47441Y165748D02*
Y177559D01*
G01X23031Y221260D02*
X21063Y219292D01*
G01X23031Y221260D02*
X63189D01*
G01X0Y272835D02*
G03X3937Y268898I3937J0D01*
G01X21063Y264961D02*
G03X17126Y268898I-3937J0D01*
G01X3937D02*
X17126D01*
G01X299409Y235040D02*
X23031D01*
G01X21063Y237008D02*
X23031Y235040D01*
G01X21063Y237008D02*
Y264961D01*
G01X0Y337796D02*
Y272835D01*
G01D02*
G03X-7874I-3937J0D01*
G01Y268898D02*
G03X-10433Y265210I1378J-3688D01*
G01X-7874Y268898D02*
Y272835D01*
G01X3937Y341733D02*
G03X0Y337796I0J-3937D01*
G01X3937Y341733D02*
X143701D01*
G01X-7874Y303543D02*
Y357781D01*
G01Y303544D02*
G03X0I3937J0D01*
G01X47441Y400788D02*
G03X51378Y396851I3937J0D01*
G01X47441Y400788D02*
Y412599D01*
G01X0Y353544D02*
G03X3937Y349607I3937J0D01*
G01Y392422D02*
G03X0Y388485I0J-3937D01*
G01X17126Y392422D02*
G03X21063Y396359I0J3937D01*
G01X0Y353544D02*
Y388485D01*
G01X21063Y454331D02*
Y396359D01*
G01D02*
Y422441D01*
G01X143701Y349607D02*
X3937D01*
G01Y392422D02*
X17126D01*
G01X-7874Y388480D02*
Y392422D01*
G01Y388485D02*
G03X0I3937J0D01*
G01Y357776D02*
G03X-7874I-3937J0D01*
G01X-10433Y396110D02*
G03X-7874Y392422I3937J0D01*
G01X-10433Y500250D02*
Y396110D01*
G01X51378Y416536D02*
G03X47441Y412599I0J-3937D01*
G01X23031Y456300D02*
X21063Y454331D01*
G01X23031Y456300D02*
X63189D01*
G01X0Y507874D02*
G03X3937Y503937I3937J0D01*
G01X21063Y500000D02*
G03X17126Y503937I-3937J0D01*
G01X3937D02*
X17126D01*
G01X299409Y470079D02*
X23031D01*
G01X21063Y472048D02*
X23031Y470079D01*
G01X21063Y472048D02*
Y500000D01*
G01X0Y572835D02*
Y507874D01*
G01D02*
G03X-7874I-3937J0D01*
G01Y503937D02*
Y507880D01*
G01Y503937D02*
G03X-10433Y500250I1378J-3688D01*
G01X3937Y576772D02*
G03X0Y572835I0J-3937D01*
G01X3937Y576772D02*
X143701D01*
G01X0Y588583D02*
G03X3937Y584646I3937J0D01*
G01X0Y588583D02*
Y623524D01*
G01X143701Y584646D02*
X3937D01*
G01X-7874Y538578D02*
Y592823D01*
G01Y538583D02*
G03X0I3937J0D01*
G01X51378Y651576D02*
G03X47441Y647639I0J-3937D01*
G01Y635828D02*
G03X51378Y631891I3937J0D01*
G01X47441Y635828D02*
Y647639D01*
G01X3937Y627461D02*
G03X0Y623524I0J-3937D01*
G01X17126Y627461D02*
G03X21063Y631398I0J3937D01*
G01Y689371D02*
Y631398D01*
G01D02*
Y657481D01*
G01X3937Y627461D02*
X17126D01*
G01X1830Y651994D02*
G03I-4292J0D01*
G01X-7874Y623517D02*
Y623536D01*
G01X13189Y691339D02*
Y635335D01*
G01X3937D02*
X13189D01*
G01X3937D02*
G03X-7874Y623524I0J-11811D01*
G01D02*
G03X0I3937J0D01*
G01Y592816D02*
G03X-7874I-3937J0D01*
G01X23031Y691339D02*
X21063Y689371D01*
G01X23031Y691339D02*
X63189D01*
G01X13189D02*
X-5271D01*
G01X63189Y161811D02*
G03X67126Y165748I0J3937D01*
G01X73425D02*
G03X77362Y161811I3937J0D01*
G01X89173D02*
G03X93110Y165748I0J3937D01*
G01X99409D02*
G03X103346Y161811I3937J0D01*
G01X63189D02*
X51378D01*
G01X89173D02*
X77362D01*
G01X115157D02*
X103346D01*
G01X89173Y114567D02*
G03Y106693I0J-3937D01*
G01X58465D02*
G03Y114567I0J3937D01*
G01X67126Y177559D02*
G03X63189Y181496I-3937J0D01*
G01X77362D02*
G03X73425Y177559I0J-3937D01*
G01X93110D02*
G03X89173Y181496I-3937J0D01*
G01X103346D02*
G03X99409Y177559I0J-3937D01*
G01X67126D02*
Y165748D01*
G01X73425D02*
Y177559D01*
G01X93110D02*
Y165748D01*
G01X99409D02*
Y177559D01*
G01X103346Y181496D02*
X115157D01*
G01X77362D02*
X89173D01*
G01X51378D02*
X63189D01*
G01X65157Y191930D02*
G03X72638I3740J0D01*
G01X65157Y219292D02*
Y191930D01*
G01X74606Y221260D02*
X72638Y219292D01*
G01D02*
Y191930D01*
G01X65157Y219292D02*
X63189Y221260D01*
G01X74606D02*
X350984D01*
G01X89173Y349607D02*
G03Y341733I0J-3937D01*
G01X58465D02*
G03Y349607I0J3937D01*
G01X63189Y396851D02*
G03X67126Y400788I0J3937D01*
G01X73425D02*
G03X77362Y396851I3937J0D01*
G01X89173D02*
G03X93110Y400788I0J3937D01*
G01X99409D02*
G03X103346Y396851I3937J0D01*
G01X67126Y412599D02*
Y400788D01*
G01X73425D02*
Y412599D01*
G01X93110D02*
Y400788D01*
G01X99409D02*
Y412599D01*
G01X63189Y396851D02*
X51378D01*
G01X89173D02*
X77362D01*
G01X115157D02*
X103346D01*
G01X67126Y412599D02*
G03X63189Y416536I-3937J0D01*
G01X77362D02*
G03X73425Y412599I0J-3937D01*
G01X93110D02*
G03X89173Y416536I-3937J0D01*
G01X103346D02*
G03X99409Y412599I0J-3937D01*
G01X103346Y416536D02*
X115157D01*
G01X77362D02*
X89173D01*
G01X51378D02*
X63189D01*
G01X65157Y426969D02*
G03X72638I3740J0D01*
G01X65157Y454331D02*
Y426969D01*
G01X74606Y456300D02*
X72638Y454331D01*
G01D02*
Y426969D01*
G01X65157Y454331D02*
X63189Y456300D01*
G01X74606D02*
X350984D01*
G01X89173Y584646D02*
G03Y576772I0J-3937D01*
G01X58465D02*
G03Y584646I0J3937D01*
G01X67126Y647639D02*
G03X63189Y651576I-3937J0D01*
G01Y631891D02*
G03X67126Y635828I0J3937D01*
G01X73425D02*
G03X77362Y631891I3937J0D01*
G01Y651576D02*
G03X73425Y647639I0J-3937D01*
G01X93110D02*
G03X89173Y651576I-3937J0D01*
G01Y631891D02*
G03X93110Y635828I0J3937D01*
G01X103346Y651576D02*
G03X99409Y647639I0J-3937D01*
G01Y635828D02*
G03X103346Y631891I3937J0D01*
G01X67126Y647639D02*
Y635828D01*
G01X73425D02*
Y647639D01*
G01X93110D02*
Y635828D01*
G01X99409D02*
Y647639D01*
G01X63189Y631891D02*
X51378D01*
G01X89173D02*
X77362D01*
G01X115157D02*
X103346D01*
G01Y651576D02*
X115157D01*
G01X77362D02*
X89173D01*
G01X51378D02*
X63189D01*
G01X65157Y662009D02*
G03X72638I3740J0D01*
G01X65157Y689371D02*
Y662009D01*
G01X74606Y691339D02*
X72638Y689371D01*
G01D02*
Y662009D01*
G01X65157Y689371D02*
X63189Y691339D01*
G01X74606D02*
X350984D01*
G01X147638Y102756D02*
G03X151575Y98819I3937J0D01*
G01X147638Y102756D02*
G03X143701Y106693I-3937J0D01*
G01X147638Y102756D02*
G03X151575Y98819I3937J0D01*
G01X147638Y102756D02*
G03X143701Y106693I-3937J0D01*
G01X147638Y102756D02*
G03X151575Y98819I3937J0D01*
G01X147638Y102756D02*
G03X143701Y106693I-3937J0D01*
G01X151575Y98819D02*
X222441D01*
G01X115157Y161811D02*
G03X119094Y165748I0J3937D01*
G01X151575Y122441D02*
G03X147638Y118504I0J-3937D01*
G01X143701Y114567D02*
G03X147638Y118504I0J3937D01*
G01X143701Y114567D02*
X112205D01*
G01X143701D02*
G03X147638Y118504I0J3937D01*
G01X151575Y122441D02*
G03X147638Y118504I0J-3937D01*
G01X151575Y122441D02*
G03X147638Y118504I0J-3937D01*
G01X143701Y114567D02*
G03X147638Y118504I0J3937D01*
G01X222441Y122441D02*
X151575D01*
G01X143701Y106693D02*
X112205D01*
G01X119094Y177559D02*
G03X115157Y181496I-3937J0D01*
G01X119094Y177559D02*
Y165748D01*
G01X147638Y337796D02*
G03X151575Y333859I3937J0D01*
G01X147638Y337796D02*
G03X143701Y341733I-3937J0D01*
G01D02*
X112205D01*
G01X147638Y337796D02*
G03X151575Y333859I3937J0D01*
G01X147638Y337796D02*
G03X143701Y341733I-3937J0D01*
G01X147638Y337796D02*
G03X151575Y333859I3937J0D01*
G01X147638Y337796D02*
G03X143701Y341733I-3937J0D01*
G01X151575Y333859D02*
X222441D01*
G01X115157Y396851D02*
G03X119094Y400788I0J3937D01*
G01Y412599D02*
Y400788D01*
G01X151575Y357481D02*
G03X147638Y353544I0J-3937D01*
G01X143701Y349607D02*
G03X147638Y353544I0J3937D01*
G01X143701Y349607D02*
X112205D01*
G01X143701D02*
G03X147638Y353544I0J3937D01*
G01X151575Y357481D02*
G03X147638Y353544I0J-3937D01*
G01X151575Y357481D02*
G03X147638Y353544I0J-3937D01*
G01X143701Y349607D02*
G03X147638Y353544I0J3937D01*
G01X222441Y357481D02*
X151575D01*
G01X119094Y412599D02*
G03X115157Y416536I-3937J0D01*
G01X147638Y572835D02*
G03X151575Y568898I3937J0D01*
G01X147638Y572835D02*
G03X143701Y576772I-3937J0D01*
G01D02*
X112205D01*
G01X147638Y572835D02*
G03X151575Y568898I3937J0D01*
G01X147638Y572835D02*
G03X143701Y576772I-3937J0D01*
G01X147638Y572835D02*
G03X151575Y568898I3937J0D01*
G01X147638Y572835D02*
G03X143701Y576772I-3937J0D01*
G01X151575Y568898D02*
X222441D01*
G01X151575Y592520D02*
G03X147638Y588583I0J-3937D01*
G01X143701Y584646D02*
G03X147638Y588583I0J3937D01*
G01X143701Y584646D02*
X112205D01*
G01X143701D02*
G03X147638Y588583I0J3937D01*
G01X151575Y592520D02*
G03X147638Y588583I0J-3937D01*
G01X151575Y592520D02*
G03X147638Y588583I0J-3937D01*
G01X143701Y584646D02*
G03X147638Y588583I0J3937D01*
G01X119094Y647639D02*
G03X115157Y651576I-3937J0D01*
G01Y631891D02*
G03X119094Y635828I0J3937D01*
G01Y647639D02*
Y635828D01*
G01X222441Y592520D02*
X151575D01*
G01X222441Y98819D02*
G03X226378Y102756I0J3937D01*
G01X230315Y106693D02*
G03X226378Y102756I0J-3937D01*
G01X230315Y106693D02*
G03X226378Y102756I0J-3937D01*
G01X222441Y98819D02*
G03X226378Y102756I0J3937D01*
G01X222441Y98819D02*
G03X226378Y102756I0J3937D01*
G01X230315Y106693D02*
G03X226378Y102756I0J-3937D01*
G01Y118504D02*
G03X222441Y122441I-3937J0D01*
G01X226378Y118504D02*
G03X230315Y114567I3937J0D01*
G01D02*
X261811D01*
G01X226378Y118504D02*
G03X222441Y122441I-3937J0D01*
G01X226378Y118504D02*
G03X230315Y114567I3937J0D01*
G01X226378Y118504D02*
G03X222441Y122441I-3937J0D01*
G01X226378Y118504D02*
G03X230315Y114567I3937J0D01*
G01X370079D02*
X230315D01*
G01Y106693D02*
X261811D01*
G01X230315D02*
X370079D01*
G01X222441Y333859D02*
G03X226378Y337796I0J3937D01*
G01X230315Y341733D02*
G03X226378Y337796I0J-3937D01*
G01X230315Y341733D02*
X261811D01*
G01X230315D02*
G03X226378Y337796I0J-3937D01*
G01X222441Y333859D02*
G03X226378Y337796I0J3937D01*
G01X222441Y333859D02*
G03X226378Y337796I0J3937D01*
G01X230315Y341733D02*
G03X226378Y337796I0J-3937D01*
G01X230315Y341733D02*
X370079D01*
G01X226378Y353544D02*
G03X222441Y357481I-3937J0D01*
G01X226378Y353544D02*
G03X230315Y349607I3937J0D01*
G01D02*
X261811D01*
G01X226378Y353544D02*
G03X222441Y357481I-3937J0D01*
G01X226378Y353544D02*
G03X230315Y349607I3937J0D01*
G01X226378Y353544D02*
G03X222441Y357481I-3937J0D01*
G01X226378Y353544D02*
G03X230315Y349607I3937J0D01*
G01X370079D02*
X230315D01*
G01X222441Y568898D02*
G03X226378Y572835I0J3937D01*
G01X230315Y576772D02*
G03X226378Y572835I0J-3937D01*
G01X230315Y576772D02*
X261811D01*
G01X230315D02*
G03X226378Y572835I0J-3937D01*
G01X222441Y568898D02*
G03X226378Y572835I0J3937D01*
G01X222441Y568898D02*
G03X226378Y572835I0J3937D01*
G01X230315Y576772D02*
G03X226378Y572835I0J-3937D01*
G01X230315Y576772D02*
X370079D01*
G01X226378Y588583D02*
G03X222441Y592520I-3937J0D01*
G01X226378Y588583D02*
G03X230315Y584646I3937J0D01*
G01D02*
X261811D01*
G01X226378Y588583D02*
G03X222441Y592520I-3937J0D01*
G01X226378Y588583D02*
G03X230315Y584646I3937J0D01*
G01X226378Y588583D02*
G03X222441Y592520I-3937J0D01*
G01X226378Y588583D02*
G03X230315Y584646I3937J0D01*
G01X370079D02*
X230315D01*
G01X280906Y43701D02*
G03X284843Y39764I3937J0D01*
G01X270669D02*
G03X274606Y43701I0J3937D01*
G01X254921D02*
G03X258858Y39764I3937J0D01*
G01X270669D02*
X258858D01*
G01X296654D02*
X284843D01*
G01Y59449D02*
G03X280906Y55512I0J-3937D01*
G01X258858Y59449D02*
G03X254921Y55512I0J-3937D01*
G01X274606D02*
G03X270669Y59449I-3937J0D01*
G01X280906Y43701D02*
Y55512D01*
G01X274606D02*
Y43701D01*
G01X254921D02*
Y55512D01*
G01X284843Y59449D02*
X296654D01*
G01X258858D02*
X270669D01*
G01X284843Y106693D02*
G03Y114567I0J3937D01*
G01X280906Y278741D02*
G03X284843Y274804I3937J0D01*
G01X270669D02*
G03X274606Y278741I0J3937D01*
G01X254921D02*
G03X258858Y274804I3937J0D01*
G01X280906Y278741D02*
Y290552D01*
G01X274606D02*
Y278741D01*
G01X254921D02*
Y290552D01*
G01X270669Y274804D02*
X258858D01*
G01X296654D02*
X284843D01*
G01Y294489D02*
G03X280906Y290552I0J-3937D01*
G01X258858Y294489D02*
G03X254921Y290552I0J-3937D01*
G01X274606D02*
G03X270669Y294489I-3937J0D01*
G01X284843D02*
X296654D01*
G01X258858D02*
X270669D01*
G01X284843Y341733D02*
G03Y349607I0J3937D01*
G01X280906Y513780D02*
G03X284843Y509843I3937J0D01*
G01Y529528D02*
G03X280906Y525591I0J-3937D01*
G01X270669Y509843D02*
G03X274606Y513780I0J3937D01*
G01X254921D02*
G03X258858Y509843I3937J0D01*
G01Y529528D02*
G03X254921Y525591I0J-3937D01*
G01X274606D02*
G03X270669Y529528I-3937J0D01*
G01X280906Y513780D02*
Y525591D01*
G01X274606D02*
Y513780D01*
G01X254921D02*
Y525591D01*
G01X284843Y529528D02*
X296654D01*
G01X258858D02*
X270669D01*
G01Y509843D02*
X258858D01*
G01X296654D02*
X284843D01*
G01Y576772D02*
G03Y584646I0J3937D01*
G01X322638Y39764D02*
G03X326575Y43701I0J3937D01*
G01X306890D02*
G03X310827Y39764I3937J0D01*
G01X296654D02*
G03X300591Y43701I0J3937D01*
G01X322638Y39764D02*
X310827D01*
G01X308858Y29331D02*
G03X301378I-3740J0D01*
G01X350984Y0D02*
X352953Y1969D01*
G01X308858D02*
Y29331D01*
G01X299409Y0D02*
X301378Y1969D01*
G01D02*
Y29331D01*
G01X308858Y1969D02*
X310827Y0D01*
G01X350984D02*
X310827D01*
G01Y59449D02*
G03X306890Y55512I0J-3937D01*
G01X326575D02*
G03X322638Y59449I-3937J0D01*
G01X300591Y55512D02*
G03X296654Y59449I-3937J0D01*
G01X326575Y55512D02*
Y43701D01*
G01X306890D02*
Y55512D01*
G01X300591D02*
Y43701D01*
G01X310827Y59449D02*
X322638D01*
G01X315551Y114567D02*
G03Y106693I0J-3937D01*
G01X352953Y219292D02*
X350984Y221260D01*
G01X322638Y274804D02*
G03X326575Y278741I0J3937D01*
G01X306890D02*
G03X310827Y274804I3937J0D01*
G01X296654D02*
G03X300591Y278741I0J3937D01*
G01X326575Y290552D02*
Y278741D01*
G01X306890D02*
Y290552D01*
G01X300591D02*
Y278741D01*
G01X322638Y274804D02*
X310827D01*
G01X308858Y264370D02*
G03X301378I-3740J0D01*
G01X350984Y235040D02*
X352953Y237008D01*
G01X308858D02*
Y264370D01*
G01X299409Y235040D02*
X301378Y237008D01*
G01D02*
Y264370D01*
G01X308858Y237008D02*
X310827Y235040D01*
G01X350984D02*
X310827D01*
G01Y294489D02*
G03X306890Y290552I0J-3937D01*
G01X326575D02*
G03X322638Y294489I-3937J0D01*
G01X300591Y290552D02*
G03X296654Y294489I-3937J0D01*
G01X310827D02*
X322638D01*
G01X315551Y349607D02*
G03Y341733I0J-3937D01*
G01X352953Y454331D02*
X350984Y456300D01*
G01X322638Y509843D02*
G03X326575Y513780I0J3937D01*
G01X306890D02*
G03X310827Y509843I3937J0D01*
G01Y529528D02*
G03X306890Y525591I0J-3937D01*
G01X326575D02*
G03X322638Y529528I-3937J0D01*
G01X300591Y525591D02*
G03X296654Y529528I-3937J0D01*
G01Y509843D02*
G03X300591Y513780I0J3937D01*
G01X326575Y525591D02*
Y513780D01*
G01X306890D02*
Y525591D01*
G01X300591D02*
Y513780D01*
G01X310827Y529528D02*
X322638D01*
G01Y509843D02*
X310827D01*
G01X308858Y499410D02*
G03X301378I-3740J0D01*
G01X350984Y470079D02*
X352953Y472048D01*
G01X308858D02*
Y499410D01*
G01X299409Y470079D02*
X301378Y472048D01*
G01D02*
Y499410D01*
G01X308858Y472048D02*
X310827Y470079D01*
G01X350984D02*
X310827D01*
G01X315551Y584646D02*
G03Y576772I0J-3937D01*
G01X352953Y689371D02*
X350984Y691339D01*
G01X381890Y37795D02*
G03X385827Y33858I3937J0D01*
G01X402953Y29921D02*
G03X399016Y33858I-3937J0D01*
G01X385827D02*
X399016D01*
G01X681299Y0D02*
X404921D01*
G01X402953Y1969D02*
X404921Y0D01*
G01X402953Y1969D02*
Y29921D01*
G01X381890Y102756D02*
Y37795D01*
G01X352953Y1969D02*
Y59941D01*
G01D02*
Y33858D01*
G01X385827Y106693D02*
G03X381890Y102756I0J-3937D01*
G01X374016D02*
G03X370079Y106693I-3937J0D01*
G01Y63878D02*
G03X374016Y67815I0J3937D01*
G01X356890Y63878D02*
G03X352953Y59941I0J-3937D01*
G01X374016Y102756D02*
Y67815D01*
G01X370079Y63878D02*
X356890D01*
G01X374016Y98524D02*
G03X381890I3937J0D01*
G01Y67815D02*
G03X374016I-3937J0D01*
G01X385827Y106693D02*
X525591D01*
G01X370079Y114567D02*
G03X374016Y118504I0J3937D01*
G01D02*
Y183465D01*
G01X381890Y118504D02*
G03X385827Y114567I3937J0D01*
G01Y157382D02*
G03X381890Y153445I0J-3937D01*
G01X399016Y157382D02*
G03X402953Y161319I0J3937D01*
G01X381890Y118504D02*
Y153445D01*
G01X402953Y219292D02*
Y161319D01*
G01D02*
Y187402D01*
G01X525591Y114567D02*
X385827D01*
G01Y157382D02*
X399016D01*
G01X374016Y153445D02*
G03X381890I3937J0D01*
G01Y122737D02*
G03X374016I-3937J0D01*
G01Y183465D02*
G03X370079Y187402I-3937J0D01*
G01X352953Y191339D02*
G03X356890Y187402I3937J0D01*
G01X370079D02*
X356890D01*
G01X352953Y219292D02*
Y191339D01*
G01X404921Y221260D02*
X402953Y219292D01*
G01X404921Y221260D02*
X445079D01*
G01X352953Y237008D02*
Y294981D01*
G01D02*
Y268898D01*
G01X381890Y272835D02*
G03X385827Y268898I3937J0D01*
G01X402953Y264961D02*
G03X399016Y268898I-3937J0D01*
G01X385827D02*
X399016D01*
G01X681299Y235040D02*
X404921D01*
G01X402953Y237008D02*
X404921Y235040D01*
G01X402953Y237008D02*
Y264961D01*
G01X381890Y337796D02*
Y272835D01*
G01X374016Y337796D02*
G03X370079Y341733I-3937J0D01*
G01Y298918D02*
G03X374016Y302855I0J3937D01*
G01X356890Y298918D02*
G03X352953Y294981I0J-3937D01*
G01X374016Y337796D02*
Y302855D01*
G01X370079Y298918D02*
X356890D01*
G01X385827Y341733D02*
G03X381890Y337796I0J-3937D01*
G01X385827Y341733D02*
X525591D01*
G01X374016Y333563D02*
G03X381890I3937J0D01*
G01Y302855D02*
G03X374016I-3937J0D01*
G01X381890Y353544D02*
G03X385827Y349607I3937J0D01*
G01Y392422D02*
G03X381890Y388485I0J-3937D01*
G01X399016Y392422D02*
G03X402953Y396359I0J3937D01*
G01X381890Y353544D02*
Y388485D01*
G01X402953Y454331D02*
Y396359D01*
G01D02*
Y422441D01*
G01X525591Y349607D02*
X385827D01*
G01Y392422D02*
X399016D01*
G01X370079Y349607D02*
G03X374016Y353544I0J3937D01*
G01D02*
Y418504D01*
G01Y388485D02*
G03X381890I3937J0D01*
G01Y357776D02*
G03X374016I-3937J0D01*
G01X404921Y456300D02*
X402953Y454331D01*
G01X404921Y456300D02*
X445079D01*
G01X374016Y418504D02*
G03X370079Y422441I-3937J0D01*
G01X352953Y426378D02*
G03X356890Y422441I3937J0D01*
G01X370079D02*
X356890D01*
G01X352953Y454331D02*
Y426378D01*
G01Y472048D02*
Y530020D01*
G01D02*
Y503937D01*
G01X381890Y507874D02*
G03X385827Y503937I3937J0D01*
G01X402953Y500000D02*
G03X399016Y503937I-3937J0D01*
G01X385827D02*
X399016D01*
G01X681299Y470079D02*
X404921D01*
G01X402953Y472048D02*
X404921Y470079D01*
G01X402953Y472048D02*
Y500000D01*
G01X381890Y572835D02*
Y507874D01*
G01X374016Y572835D02*
G03X370079Y576772I-3937J0D01*
G01Y533957D02*
G03X374016Y537894I0J3937D01*
G01X356890Y533957D02*
G03X352953Y530020I0J-3937D01*
G01X374016Y572835D02*
Y537894D01*
G01X370079Y533957D02*
X356890D01*
G01X385827Y576772D02*
G03X381890Y572835I0J-3937D01*
G01X385827Y576772D02*
X525591D01*
G01X381890Y588583D02*
G03X385827Y584646I3937J0D01*
G01X381890Y588583D02*
Y623524D01*
G01X525591Y584646D02*
X385827D01*
G01X370079D02*
G03X374016Y588583I0J3937D01*
G01D02*
Y653544D01*
G01Y568603D02*
G03X381890I3937J0D01*
G01Y537894D02*
G03X374016I-3937J0D01*
G01X385827Y627461D02*
G03X381890Y623524I0J-3937D01*
G01X399016Y627461D02*
G03X402953Y631398I0J3937D01*
G01Y689371D02*
Y631398D01*
G01D02*
Y657481D01*
G01X385827Y627461D02*
X399016D01*
G01X374016Y623524D02*
G03X381890I3937J0D01*
G01Y592816D02*
G03X374016I-3937J0D01*
G01X404921Y691339D02*
X402953Y689371D01*
G01X404921Y691339D02*
X445079D01*
G01X374016Y653544D02*
G03X370079Y657481I-3937J0D01*
G01X352953Y661418D02*
G03X356890Y657481I3937J0D01*
G01X370079D02*
X356890D01*
G01X352953Y689371D02*
Y661418D01*
G01X445079Y161811D02*
G03X449016Y165748I0J3937D01*
G01X429331D02*
G03X433268Y161811I3937J0D01*
G01X455315Y165748D02*
G03X459252Y161811I3937J0D01*
G01X471063D02*
G03X475000Y165748I0J3937D01*
G01X445079Y161811D02*
X433268D01*
G01X471063D02*
X459252D01*
G01X471063Y114567D02*
G03Y106693I0J-3937D01*
G01X440354D02*
G03Y114567I0J3937D01*
G01X433268Y181496D02*
G03X429331Y177559I0J-3937D01*
G01X449016D02*
G03X445079Y181496I-3937J0D01*
G01X459252D02*
G03X455315Y177559I0J-3937D01*
G01X475000D02*
G03X471063Y181496I-3937J0D01*
G01X429331Y165748D02*
Y177559D01*
G01X449016D02*
Y165748D01*
G01X455315D02*
Y177559D01*
G01X459252Y181496D02*
X471063D01*
G01X433268D02*
X445079D01*
G01X447047Y191930D02*
G03X454528I3740J0D01*
G01X447047Y219292D02*
Y191930D01*
G01X456496Y221260D02*
X454528Y219292D01*
G01D02*
Y191930D01*
G01X447047Y219292D02*
X445079Y221260D01*
G01X456496D02*
X732874D01*
G01X471063Y349607D02*
G03Y341733I0J-3937D01*
G01X440354D02*
G03Y349607I0J3937D01*
G01X445079Y396851D02*
G03X449016Y400788I0J3937D01*
G01X429331D02*
G03X433268Y396851I3937J0D01*
G01X455315Y400788D02*
G03X459252Y396851I3937J0D01*
G01X471063D02*
G03X475000Y400788I0J3937D01*
G01X429331D02*
Y412599D01*
G01X449016D02*
Y400788D01*
G01X455315D02*
Y412599D01*
G01X445079Y396851D02*
X433268D01*
G01X471063D02*
X459252D01*
G01X433268Y416536D02*
G03X429331Y412599I0J-3937D01*
G01X449016D02*
G03X445079Y416536I-3937J0D01*
G01X459252D02*
G03X455315Y412599I0J-3937D01*
G01X475000D02*
G03X471063Y416536I-3937J0D01*
G01X459252D02*
X471063D01*
G01X433268D02*
X445079D01*
G01X447047Y426969D02*
G03X454528I3740J0D01*
G01X447047Y454331D02*
Y426969D01*
G01X456496Y456300D02*
X454528Y454331D01*
G01D02*
Y426969D01*
G01X447047Y454331D02*
X445079Y456300D01*
G01X456496D02*
X732874D01*
G01X471063Y584646D02*
G03Y576772I0J-3937D01*
G01X440354D02*
G03Y584646I0J3937D01*
G01X433268Y651576D02*
G03X429331Y647639I0J-3937D01*
G01X449016D02*
G03X445079Y651576I-3937J0D01*
G01Y631891D02*
G03X449016Y635828I0J3937D01*
G01X429331D02*
G03X433268Y631891I3937J0D01*
G01X455315Y635828D02*
G03X459252Y631891I3937J0D01*
G01Y651576D02*
G03X455315Y647639I0J-3937D01*
G01X475000D02*
G03X471063Y651576I-3937J0D01*
G01Y631891D02*
G03X475000Y635828I0J3937D01*
G01X429331D02*
Y647639D01*
G01X449016D02*
Y635828D01*
G01X455315D02*
Y647639D01*
G01X445079Y631891D02*
X433268D01*
G01X471063D02*
X459252D01*
G01Y651576D02*
X471063D01*
G01X433268D02*
X445079D01*
G01X447047Y662009D02*
G03X454528I3740J0D01*
G01X447047Y689371D02*
Y662009D01*
G01X456496Y691339D02*
X454528Y689371D01*
G01D02*
Y662009D01*
G01X447047Y689371D02*
X445079Y691339D01*
G01X456496D02*
X732874D01*
G01X529528Y102756D02*
G03X533465Y98819I3937J0D01*
G01X529528Y102756D02*
G03X525591Y106693I-3937J0D01*
G01X529528Y102756D02*
G03X533465Y98819I3937J0D01*
G01X529528Y102756D02*
G03X525591Y106693I-3937J0D01*
G01X529528Y102756D02*
G03X533465Y98819I3937J0D01*
G01X529528Y102756D02*
G03X525591Y106693I-3937J0D01*
G01X533465Y98819D02*
X604331D01*
G01X525591Y106693D02*
X494094D01*
G01X497047Y161811D02*
G03X500984Y165748I0J3937D01*
G01X481299D02*
G03X485236Y161811I3937J0D01*
G01X497047D02*
X485236D01*
G01X533465Y122441D02*
G03X529528Y118504I0J-3937D01*
G01X525591Y114567D02*
G03X529528Y118504I0J3937D01*
G01X525591Y114567D02*
X494094D01*
G01X525591D02*
G03X529528Y118504I0J3937D01*
G01X533465Y122441D02*
G03X529528Y118504I0J-3937D01*
G01X533465Y122441D02*
G03X529528Y118504I0J-3937D01*
G01X525591Y114567D02*
G03X529528Y118504I0J3937D01*
G01X604331Y122441D02*
X533465D01*
G01X485236Y181496D02*
G03X481299Y177559I0J-3937D01*
G01X500984D02*
G03X497047Y181496I-3937J0D01*
G01X475000Y177559D02*
Y165748D01*
G01X481299D02*
Y177559D01*
G01X500984D02*
Y165748D01*
G01X485236Y181496D02*
X497047D01*
G01X529528Y337796D02*
G03X533465Y333859I3937J0D01*
G01X529528Y337796D02*
G03X525591Y341733I-3937J0D01*
G01D02*
X494094D01*
G01X529528Y337796D02*
G03X533465Y333859I3937J0D01*
G01X529528Y337796D02*
G03X525591Y341733I-3937J0D01*
G01X529528Y337796D02*
G03X533465Y333859I3937J0D01*
G01X529528Y337796D02*
G03X525591Y341733I-3937J0D01*
G01X533465Y333859D02*
X604331D01*
G01X497047Y396851D02*
G03X500984Y400788I0J3937D01*
G01X481299D02*
G03X485236Y396851I3937J0D01*
G01X475000Y412599D02*
Y400788D01*
G01X481299D02*
Y412599D01*
G01X500984D02*
Y400788D01*
G01X497047Y396851D02*
X485236D01*
G01X533465Y357481D02*
G03X529528Y353544I0J-3937D01*
G01X525591Y349607D02*
G03X529528Y353544I0J3937D01*
G01X525591Y349607D02*
X494094D01*
G01X525591D02*
G03X529528Y353544I0J3937D01*
G01X533465Y357481D02*
G03X529528Y353544I0J-3937D01*
G01X533465Y357481D02*
G03X529528Y353544I0J-3937D01*
G01X525591Y349607D02*
G03X529528Y353544I0J3937D01*
G01X604331Y357481D02*
X533465D01*
G01X485236Y416536D02*
G03X481299Y412599I0J-3937D01*
G01X500984D02*
G03X497047Y416536I-3937J0D01*
G01X485236D02*
X497047D01*
G01X529528Y572835D02*
G03X533465Y568898I3937J0D01*
G01X529528Y572835D02*
G03X525591Y576772I-3937J0D01*
G01D02*
X494094D01*
G01X529528Y572835D02*
G03X533465Y568898I3937J0D01*
G01X529528Y572835D02*
G03X525591Y576772I-3937J0D01*
G01X529528Y572835D02*
G03X533465Y568898I3937J0D01*
G01X529528Y572835D02*
G03X525591Y576772I-3937J0D01*
G01X533465Y568898D02*
X604331D01*
G01X533465Y592520D02*
G03X529528Y588583I0J-3937D01*
G01X525591Y584646D02*
G03X529528Y588583I0J3937D01*
G01X525591Y584646D02*
X494094D01*
G01X525591D02*
G03X529528Y588583I0J3937D01*
G01X533465Y592520D02*
G03X529528Y588583I0J-3937D01*
G01X533465Y592520D02*
G03X529528Y588583I0J-3937D01*
G01X525591Y584646D02*
G03X529528Y588583I0J3937D01*
G01X485236Y651576D02*
G03X481299Y647639I0J-3937D01*
G01X500984D02*
G03X497047Y651576I-3937J0D01*
G01Y631891D02*
G03X500984Y635828I0J3937D01*
G01X481299D02*
G03X485236Y631891I3937J0D01*
G01X475000Y647639D02*
Y635828D01*
G01X481299D02*
Y647639D01*
G01X500984D02*
Y635828D01*
G01X497047Y631891D02*
X485236D01*
G01Y651576D02*
X497047D01*
G01X604331Y592520D02*
X533465D01*
G01X652559Y39764D02*
G03X656496Y43701I0J3937D01*
G01X636811D02*
G03X640748Y39764I3937J0D01*
G01X652559D02*
X640748D01*
G01Y59449D02*
G03X636811Y55512I0J-3937D01*
G01X656496D02*
G03X652559Y59449I-3937J0D01*
G01X656496Y55512D02*
Y43701D01*
G01X636811D02*
Y55512D01*
G01X640748Y59449D02*
X652559D01*
G01X604331Y98819D02*
G03X608268Y102756I0J3937D01*
G01X612205Y106693D02*
G03X608268Y102756I0J-3937D01*
G01X612205Y106693D02*
G03X608268Y102756I0J-3937D01*
G01X604331Y98819D02*
G03X608268Y102756I0J3937D01*
G01X604331Y98819D02*
G03X608268Y102756I0J3937D01*
G01X612205Y106693D02*
G03X608268Y102756I0J-3937D01*
G01X612205Y106693D02*
X643701D01*
G01X612205D02*
X751969D01*
G01X608268Y118504D02*
G03X604331Y122441I-3937J0D01*
G01X608268Y118504D02*
G03X612205Y114567I3937J0D01*
G01D02*
X643701D01*
G01X608268Y118504D02*
G03X604331Y122441I-3937J0D01*
G01X608268Y118504D02*
G03X612205Y114567I3937J0D01*
G01X608268Y118504D02*
G03X604331Y122441I-3937J0D01*
G01X608268Y118504D02*
G03X612205Y114567I3937J0D01*
G01X751969D02*
X612205D01*
G01X652559Y274804D02*
G03X656496Y278741I0J3937D01*
G01X636811D02*
G03X640748Y274804I3937J0D01*
G01X656496Y290552D02*
Y278741D01*
G01X636811D02*
Y290552D01*
G01X652559Y274804D02*
X640748D01*
G01Y294489D02*
G03X636811Y290552I0J-3937D01*
G01X656496D02*
G03X652559Y294489I-3937J0D01*
G01X640748D02*
X652559D01*
G01X604331Y333859D02*
G03X608268Y337796I0J3937D01*
G01X612205Y341733D02*
G03X608268Y337796I0J-3937D01*
G01X612205Y341733D02*
X643701D01*
G01X612205D02*
G03X608268Y337796I0J-3937D01*
G01X604331Y333859D02*
G03X608268Y337796I0J3937D01*
G01X604331Y333859D02*
G03X608268Y337796I0J3937D01*
G01X612205Y341733D02*
G03X608268Y337796I0J-3937D01*
G01X612205Y341733D02*
X751969D01*
G01X608268Y353544D02*
G03X604331Y357481I-3937J0D01*
G01X608268Y353544D02*
G03X612205Y349607I3937J0D01*
G01D02*
X643701D01*
G01X608268Y353544D02*
G03X604331Y357481I-3937J0D01*
G01X608268Y353544D02*
G03X612205Y349607I3937J0D01*
G01X608268Y353544D02*
G03X604331Y357481I-3937J0D01*
G01X608268Y353544D02*
G03X612205Y349607I3937J0D01*
G01X751969D02*
X612205D01*
G01X652559Y509843D02*
G03X656496Y513780I0J3937D01*
G01X636811D02*
G03X640748Y509843I3937J0D01*
G01Y529528D02*
G03X636811Y525591I0J-3937D01*
G01X656496D02*
G03X652559Y529528I-3937J0D01*
G01X656496Y525591D02*
Y513780D01*
G01X636811D02*
Y525591D01*
G01X640748Y529528D02*
X652559D01*
G01Y509843D02*
X640748D01*
G01X604331Y568898D02*
G03X608268Y572835I0J3937D01*
G01X612205Y576772D02*
G03X608268Y572835I0J-3937D01*
G01X612205Y576772D02*
X643701D01*
G01X612205D02*
G03X608268Y572835I0J-3937D01*
G01X604331Y568898D02*
G03X608268Y572835I0J3937D01*
G01X604331Y568898D02*
G03X608268Y572835I0J3937D01*
G01X612205Y576772D02*
G03X608268Y572835I0J-3937D01*
G01X612205Y576772D02*
X751969D01*
G01X608268Y588583D02*
G03X604331Y592520I-3937J0D01*
G01X608268Y588583D02*
G03X612205Y584646I3937J0D01*
G01D02*
X643701D01*
G01X608268Y588583D02*
G03X604331Y592520I-3937J0D01*
G01X608268Y588583D02*
G03X612205Y584646I3937J0D01*
G01X608268Y588583D02*
G03X604331Y592520I-3937J0D01*
G01X608268Y588583D02*
G03X612205Y584646I3937J0D01*
G01X751969D02*
X612205D01*
G01X704528Y39764D02*
G03X708465Y43701I0J3937D01*
G01X688780D02*
G03X692717Y39764I3937J0D01*
G01X678543D02*
G03X682480Y43701I0J3937D01*
G01X662795D02*
G03X666732Y39764I3937J0D01*
G01X678543D02*
X666732D01*
G01X704528D02*
X692717D01*
G01X690748Y29331D02*
G03X683268I-3740J0D01*
G01X690748Y1969D02*
Y29331D01*
G01X681299Y0D02*
X683268Y1969D01*
G01D02*
Y29331D01*
G01X690748Y1969D02*
X692717Y0D01*
G01X732874D02*
X692717D01*
G01Y59449D02*
G03X688780Y55512I0J-3937D01*
G01X708465D02*
G03X704528Y59449I-3937J0D01*
G01X682480Y55512D02*
G03X678543Y59449I-3937J0D01*
G01X666732D02*
G03X662795Y55512I0J-3937D01*
G01X708465D02*
Y43701D01*
G01X688780D02*
Y55512D01*
G01X682480D02*
Y43701D01*
G01X662795D02*
Y55512D01*
G01X692717Y59449D02*
X704528D01*
G01X666732D02*
X678543D01*
G01X697441Y114567D02*
G03Y106693I0J-3937D01*
G01X666732D02*
G03Y114567I0J3937D01*
G01X704528Y274804D02*
G03X708465Y278741I0J3937D01*
G01X688780D02*
G03X692717Y274804I3937J0D01*
G01X678543D02*
G03X682480Y278741I0J3937D01*
G01X662795D02*
G03X666732Y274804I3937J0D01*
G01X708465Y290552D02*
Y278741D01*
G01X688780D02*
Y290552D01*
G01X682480D02*
Y278741D01*
G01X662795D02*
Y290552D01*
G01X678543Y274804D02*
X666732D01*
G01X704528D02*
X692717D01*
G01X690748Y264370D02*
G03X683268I-3740J0D01*
G01X690748Y237008D02*
Y264370D01*
G01X681299Y235040D02*
X683268Y237008D01*
G01D02*
Y264370D01*
G01X690748Y237008D02*
X692717Y235040D01*
G01X732874D02*
X692717D01*
G01Y294489D02*
G03X688780Y290552I0J-3937D01*
G01X708465D02*
G03X704528Y294489I-3937J0D01*
G01X682480Y290552D02*
G03X678543Y294489I-3937J0D01*
G01X666732D02*
G03X662795Y290552I0J-3937D01*
G01X692717Y294489D02*
X704528D01*
G01X666732D02*
X678543D01*
G01X697441Y349607D02*
G03Y341733I0J-3937D01*
G01X666732D02*
G03Y349607I0J3937D01*
G01X704528Y509843D02*
G03X708465Y513780I0J3937D01*
G01X688780D02*
G03X692717Y509843I3937J0D01*
G01Y529528D02*
G03X688780Y525591I0J-3937D01*
G01X708465D02*
G03X704528Y529528I-3937J0D01*
G01X682480Y525591D02*
G03X678543Y529528I-3937J0D01*
G01Y509843D02*
G03X682480Y513780I0J3937D01*
G01X662795D02*
G03X666732Y509843I3937J0D01*
G01Y529528D02*
G03X662795Y525591I0J-3937D01*
G01X708465D02*
Y513780D01*
G01X688780D02*
Y525591D01*
G01X682480D02*
Y513780D01*
G01X662795D02*
Y525591D01*
G01X692717Y529528D02*
X704528D01*
G01X666732D02*
X678543D01*
G01Y509843D02*
X666732D01*
G01X704528D02*
X692717D01*
G01X690748Y499410D02*
G03X683268I-3740J0D01*
G01X690748Y472048D02*
Y499410D01*
G01X681299Y470079D02*
X683268Y472048D01*
G01D02*
Y499410D01*
G01X690748Y472048D02*
X692717Y470079D01*
G01X732874D02*
X692717D01*
G01X697441Y584646D02*
G03Y576772I0J-3937D01*
G01X666732D02*
G03Y584646I0J3937D01*
G01X734843Y1969D02*
Y59941D01*
G01D02*
Y33858D01*
G01X732874Y0D02*
X734843Y1969D01*
G01X762744Y17317D02*
G03I-4292J0D01*
G01X775591Y553149D02*
Y15000D01*
G01X760591Y0D02*
G03X775591Y15000I0J15000D01*
G01X742717Y0D02*
Y56004D01*
G01Y0D02*
X760591D01*
G01X755906Y102756D02*
G03X751969Y106693I-3937J0D01*
G01Y63878D02*
G03X755906Y67815I0J3937D01*
G01X738780Y63878D02*
G03X734843Y59941I0J-3937D01*
G01X755906Y102756D02*
Y67815D01*
G01X751969Y63878D02*
X738780D01*
G01X763780Y152761D02*
Y98517D01*
G01Y67822D02*
Y67803D01*
G01X751969Y56004D02*
X742717D01*
G01X751969D02*
G03X763780Y67815I0J11811D01*
G01D02*
G03X755906I-3937J0D01*
G01Y98524D02*
G03X763780I3937J0D01*
G01X751969Y114567D02*
G03X755906Y118504I0J3937D01*
G01D02*
Y183465D01*
G01X763780Y152756D02*
G03X755906I-3937J0D01*
G01Y183465D02*
G03X751969Y187402I-3937J0D01*
G01X734843Y191339D02*
G03X738780Y187402I3937J0D01*
G01X751969D02*
X738780D01*
G01X734843Y219292D02*
X732874Y221260D01*
G01X734843Y219292D02*
Y191339D01*
G01X755906Y183465D02*
G03X763780I3937J0D01*
G01Y302855D02*
Y183460D01*
G01X734843Y237008D02*
Y294981D01*
G01D02*
Y268898D01*
G01X732874Y235040D02*
X734843Y237008D01*
G01X755906Y337796D02*
G03X751969Y341733I-3937J0D01*
G01Y298918D02*
G03X755906Y302855I0J3937D01*
G01X738780Y298918D02*
G03X734843Y294981I0J-3937D01*
G01X755906Y337796D02*
Y302855D01*
G01X751969Y298918D02*
X738780D01*
G01X763780Y387796D02*
Y333559D01*
G01Y302855D02*
G03X755906I-3937J0D01*
G01Y333563D02*
G03X763780I3937J0D01*
G01X751969Y349607D02*
G03X755906Y353544I0J3937D01*
G01D02*
Y418504D01*
G01X763780Y387796D02*
G03X755906I-3937J0D01*
G01Y418504D02*
G03X751969Y422441I-3937J0D01*
G01X734843Y426378D02*
G03X738780Y422441I3937J0D01*
G01X751969D02*
X738780D01*
G01X734843Y454331D02*
X732874Y456300D01*
G01X734843Y454331D02*
Y426378D01*
G01X763780Y537894D02*
Y418504D01*
G01X755906Y418505D02*
G03X763780I3937J0D01*
G01X734843Y472048D02*
Y530020D01*
G01D02*
Y503937D01*
G01X732874Y470079D02*
X734843Y472048D01*
G01X755906Y572835D02*
G03X751969Y576772I-3937J0D01*
G01Y533957D02*
G03X755906Y537894I0J3937D01*
G01X738780Y533957D02*
G03X734843Y530020I0J-3937D01*
G01X755906Y572835D02*
Y537894D01*
G01X751969Y533957D02*
X738780D01*
G01X751969Y584646D02*
G03X755906Y588583I0J3937D01*
G01D02*
Y653544D01*
G01X775591Y561023D02*
G03Y553149I0J-3937D01*
G01X763780Y537894D02*
G03X755906I-3937J0D01*
G01Y568603D02*
G03X763780I3937J0D01*
G01X775591Y676339D02*
Y561023D01*
G01X763780Y622835D02*
Y568603D01*
G01Y622835D02*
G03X755906I-3937J0D01*
G01Y653544D02*
G03X763780I3937J0D01*
G01X755906D02*
G03X751969Y657481I-3937J0D01*
G01X734843Y661418D02*
G03X738780Y657481I3937J0D01*
G01X751969D02*
X738780D01*
G01X734843Y689371D02*
X732874Y691339D01*
G01X734843Y689371D02*
Y661418D01*
G01X760014Y677788D02*
G03I-4292J0D01*
G01X775591Y676339D02*
G03X760591Y691339I-15000J0D01*
G01X751969Y665355D02*
X742717D01*
G01X763780Y653544D02*
G03X751969Y665355I-11811J0D01*
G01X742717Y691339D02*
X760591D01*
G01X742717Y665355D02*
Y691339D01*
M02*
